FILE_TYPE = MACRO_DRAWING;
SET COLOR_WIRE YELLOW;
SET COLOR_PROP ORANGE;
SET COLOR_DOT WHITE;
SET COLOR_ARC YELLOW;
SET COLOR_BODY GREEN;
SET COLOR_NOTE PURPLE;
SET PROP_DISPLAY VALUE;
SET PAGE_NUMBER P106;
FORCEADD UNIVERSAL_GND..1
(-2525 -400);
FORCEPROP 3 LASTPIN (-2525 -350) SIG_NAME GND\g
J 0
(-2515 -340);
DISPLAY 0.659574 (-2515 -340);
PAINT MONO (-2515 -340);
DISPLAY INVISIBLE (-2515 -340);
FORCEPROP 1 LAST PATH I1
J 0
(-2450 -400);
DISPLAY 0.872340 (-2450 -400);
PAINT AQUA (-2450 -400);
DISPLAY INVISIBLE (-2450 -400);
FORCEPROP 1 LAST HDL_POWER GND
J 1
(-2500 -475);
DISPLAY 0.872340 (-2500 -475);
PAINT GREEN (-2500 -475);
DISPLAY INVISIBLE (-2500 -475);
FORCEPROP 2 LAST CDS_LIB logical_power
J 0
(-2525 -400);
PAINT MONO (-2525 -400);
DISPLAY INVISIBLE (-2525 -400);
FORCEADD OFFPAGE..1
(-3675 1725);
FORCEPROP 2 LAST $XR3 109 
J 0
(-4047 1689);
DISPLAY 0.638298 (-4047 1689);
PAINT MONO (-4047 1689);
FORCEPROP 2 LAST $XR2 108 
J 0
(-3927 1689);
DISPLAY 0.638298 (-3927 1689);
PAINT MONO (-3927 1689);
FORCEPROP 2 LAST $XR1 107 
J 0
(-4047 1725);
DISPLAY 0.638298 (-4047 1725);
PAINT MONO (-4047 1725);
FORCEPROP 2 LAST $XR0 130 
J 0
(-3927 1725);
DISPLAY 0.638298 (-3927 1725);
PAINT MONO (-3927 1725);
FORCEPROP 2 LAST CDS_LIB standard
J 0
(-3675 1725);
PAINT MONO (-3675 1725);
DISPLAY INVISIBLE (-3675 1725);
FORCEPROP 1 LAST OFFPAGE TRUE
J 0
(-3350 1600);
DISPLAY 0.872340 (-3350 1600);
DISPLAY INVISIBLE (-3350 1600);
FORCEPROP 1 LAST COMMENT_BODY TRUE
J 0
(-3550 1625);
DISPLAY 0.872340 (-3550 1625);
PAINT GREEN (-3550 1625);
DISPLAY INVISIBLE (-3550 1625);
FORCEPROP 2 LAST PATH I10
J 0
(-3625 1800);
DISPLAY 1.021277 (-3625 1800);
DISPLAY INVISIBLE (-3625 1800);
FORCEADD TAP..1
(-1100 3025);
FORCEPROP 3 LASTPIN (-1150 3025) SIG_NAME M_E_CPU1_SA_DQ<12>
J 0
(-1140 3035);
DISPLAY 0.659574 (-1140 3035);
PAINT MONO (-1140 3035);
DISPLAY INVISIBLE (-1140 3035);
FORCEPROP 1 LASTPIN (-1150 3025) BN 12
J 0
(-1162 3033);
DISPLAY 0.680851 (-1162 3033);
PAINT GREEN (-1162 3033);
FORCEPROP 2 LAST CDS_LIB standard
J 0
(-1100 3025);
PAINT MONO (-1100 3025);
DISPLAY INVISIBLE (-1100 3025);
FORCEPROP 1 LAST BODY_TYPE PLUMBING
J 0
(-1100 3075);
DISPLAY 0.872340 (-1100 3075);
PAINT GREEN (-1100 3075);
DISPLAY INVISIBLE (-1100 3075);
FORCEPROP 1 LAST HDL_TAP TRUE
J 0
(-775 2900);
DISPLAY 0.872340 (-775 2900);
DISPLAY INVISIBLE (-775 2900);
FORCEPROP 1 LAST PATH I100
J 0
(-1102 3025);
DISPLAY 0.872340 (-1102 3025);
PAINT GREEN (-1102 3025);
DISPLAY INVISIBLE (-1102 3025);
FORCEADD TAP..1
(-1100 3125);
FORCEPROP 3 LASTPIN (-1150 3125) SIG_NAME M_E_CPU1_SA_DQ<14>
J 0
(-1140 3135);
DISPLAY 0.659574 (-1140 3135);
PAINT MONO (-1140 3135);
DISPLAY INVISIBLE (-1140 3135);
FORCEPROP 1 LASTPIN (-1150 3125) BN 14
J 0
(-1162 3133);
DISPLAY 0.680851 (-1162 3133);
PAINT GREEN (-1162 3133);
FORCEPROP 2 LAST CDS_LIB standard
J 0
(-1100 3125);
PAINT MONO (-1100 3125);
DISPLAY INVISIBLE (-1100 3125);
FORCEPROP 1 LAST BODY_TYPE PLUMBING
J 0
(-1100 3175);
DISPLAY 0.872340 (-1100 3175);
PAINT GREEN (-1100 3175);
DISPLAY INVISIBLE (-1100 3175);
FORCEPROP 1 LAST HDL_TAP TRUE
J 0
(-775 3000);
DISPLAY 0.872340 (-775 3000);
DISPLAY INVISIBLE (-775 3000);
FORCEPROP 1 LAST PATH I101
J 0
(-1102 3125);
DISPLAY 0.872340 (-1102 3125);
PAINT GREEN (-1102 3125);
DISPLAY INVISIBLE (-1102 3125);
FORCEADD TAP..1
(-1100 3075);
FORCEPROP 3 LASTPIN (-1150 3075) SIG_NAME M_E_CPU1_SA_DQ<13>
J 0
(-1140 3085);
DISPLAY 0.659574 (-1140 3085);
PAINT MONO (-1140 3085);
DISPLAY INVISIBLE (-1140 3085);
FORCEPROP 1 LASTPIN (-1150 3075) BN 13
J 0
(-1162 3083);
DISPLAY 0.680851 (-1162 3083);
PAINT GREEN (-1162 3083);
FORCEPROP 2 LAST CDS_LIB standard
J 0
(-1100 3075);
PAINT MONO (-1100 3075);
DISPLAY INVISIBLE (-1100 3075);
FORCEPROP 1 LAST BODY_TYPE PLUMBING
J 0
(-1100 3125);
DISPLAY 0.872340 (-1100 3125);
PAINT GREEN (-1100 3125);
DISPLAY INVISIBLE (-1100 3125);
FORCEPROP 1 LAST HDL_TAP TRUE
J 0
(-775 2950);
DISPLAY 0.872340 (-775 2950);
DISPLAY INVISIBLE (-775 2950);
FORCEPROP 1 LAST PATH I102
J 0
(-1102 3075);
DISPLAY 0.872340 (-1102 3075);
PAINT GREEN (-1102 3075);
DISPLAY INVISIBLE (-1102 3075);
FORCEADD TAP..1
(-1100 3275);
FORCEPROP 3 LASTPIN (-1150 3275) SIG_NAME M_E_CPU1_SA_DQ<17>
J 0
(-1140 3285);
DISPLAY 0.659574 (-1140 3285);
PAINT MONO (-1140 3285);
DISPLAY INVISIBLE (-1140 3285);
FORCEPROP 1 LASTPIN (-1150 3275) BN 17
J 0
(-1162 3283);
DISPLAY 0.680851 (-1162 3283);
PAINT GREEN (-1162 3283);
FORCEPROP 2 LAST CDS_LIB standard
J 0
(-1100 3275);
PAINT MONO (-1100 3275);
DISPLAY INVISIBLE (-1100 3275);
FORCEPROP 1 LAST BODY_TYPE PLUMBING
J 0
(-1100 3325);
DISPLAY 0.872340 (-1100 3325);
PAINT GREEN (-1100 3325);
DISPLAY INVISIBLE (-1100 3325);
FORCEPROP 1 LAST HDL_TAP TRUE
J 0
(-775 3150);
DISPLAY 0.872340 (-775 3150);
DISPLAY INVISIBLE (-775 3150);
FORCEPROP 1 LAST PATH I103
J 0
(-1102 3275);
DISPLAY 0.872340 (-1102 3275);
PAINT GREEN (-1102 3275);
DISPLAY INVISIBLE (-1102 3275);
FORCEADD TAP..1
(-1100 3175);
FORCEPROP 3 LASTPIN (-1150 3175) SIG_NAME M_E_CPU1_SA_DQ<15>
J 0
(-1140 3185);
DISPLAY 0.659574 (-1140 3185);
PAINT MONO (-1140 3185);
DISPLAY INVISIBLE (-1140 3185);
FORCEPROP 1 LASTPIN (-1150 3175) BN 15
J 0
(-1162 3183);
DISPLAY 0.680851 (-1162 3183);
PAINT GREEN (-1162 3183);
FORCEPROP 2 LAST CDS_LIB standard
J 0
(-1100 3175);
PAINT MONO (-1100 3175);
DISPLAY INVISIBLE (-1100 3175);
FORCEPROP 1 LAST BODY_TYPE PLUMBING
J 0
(-1100 3225);
DISPLAY 0.872340 (-1100 3225);
PAINT GREEN (-1100 3225);
DISPLAY INVISIBLE (-1100 3225);
FORCEPROP 1 LAST HDL_TAP TRUE
J 0
(-775 3050);
DISPLAY 0.872340 (-775 3050);
DISPLAY INVISIBLE (-775 3050);
FORCEPROP 1 LAST PATH I104
J 0
(-1102 3175);
DISPLAY 0.872340 (-1102 3175);
PAINT GREEN (-1102 3175);
DISPLAY INVISIBLE (-1102 3175);
FORCEADD TAP..1
(-1100 3225);
FORCEPROP 3 LASTPIN (-1150 3225) SIG_NAME M_E_CPU1_SA_DQ<16>
J 0
(-1140 3235);
DISPLAY 0.659574 (-1140 3235);
PAINT MONO (-1140 3235);
DISPLAY INVISIBLE (-1140 3235);
FORCEPROP 1 LASTPIN (-1150 3225) BN 16
J 0
(-1162 3233);
DISPLAY 0.680851 (-1162 3233);
PAINT GREEN (-1162 3233);
FORCEPROP 2 LAST CDS_LIB standard
J 0
(-1100 3225);
PAINT MONO (-1100 3225);
DISPLAY INVISIBLE (-1100 3225);
FORCEPROP 1 LAST BODY_TYPE PLUMBING
J 0
(-1100 3275);
DISPLAY 0.872340 (-1100 3275);
PAINT GREEN (-1100 3275);
DISPLAY INVISIBLE (-1100 3275);
FORCEPROP 1 LAST HDL_TAP TRUE
J 0
(-775 3100);
DISPLAY 0.872340 (-775 3100);
DISPLAY INVISIBLE (-775 3100);
FORCEPROP 1 LAST PATH I105
J 0
(-1102 3225);
DISPLAY 0.872340 (-1102 3225);
PAINT GREEN (-1102 3225);
DISPLAY INVISIBLE (-1102 3225);
FORCEADD TAP..1
(-1100 3375);
FORCEPROP 3 LASTPIN (-1150 3375) SIG_NAME M_E_CPU1_SA_DQ<19>
J 0
(-1140 3385);
DISPLAY 0.659574 (-1140 3385);
PAINT MONO (-1140 3385);
DISPLAY INVISIBLE (-1140 3385);
FORCEPROP 1 LASTPIN (-1150 3375) BN 19
J 0
(-1162 3383);
DISPLAY 0.680851 (-1162 3383);
PAINT GREEN (-1162 3383);
FORCEPROP 2 LAST CDS_LIB standard
J 0
(-1100 3375);
PAINT MONO (-1100 3375);
DISPLAY INVISIBLE (-1100 3375);
FORCEPROP 1 LAST BODY_TYPE PLUMBING
J 0
(-1100 3425);
DISPLAY 0.872340 (-1100 3425);
PAINT GREEN (-1100 3425);
DISPLAY INVISIBLE (-1100 3425);
FORCEPROP 1 LAST HDL_TAP TRUE
J 0
(-775 3250);
DISPLAY 0.872340 (-775 3250);
DISPLAY INVISIBLE (-775 3250);
FORCEPROP 1 LAST PATH I106
J 0
(-1102 3375);
DISPLAY 0.872340 (-1102 3375);
PAINT GREEN (-1102 3375);
DISPLAY INVISIBLE (-1102 3375);
FORCEADD TAP..1
(-1100 3325);
FORCEPROP 3 LASTPIN (-1150 3325) SIG_NAME M_E_CPU1_SA_DQ<18>
J 0
(-1140 3335);
DISPLAY 0.659574 (-1140 3335);
PAINT MONO (-1140 3335);
DISPLAY INVISIBLE (-1140 3335);
FORCEPROP 1 LASTPIN (-1150 3325) BN 18
J 0
(-1162 3333);
DISPLAY 0.680851 (-1162 3333);
PAINT GREEN (-1162 3333);
FORCEPROP 2 LAST CDS_LIB standard
J 0
(-1100 3325);
PAINT MONO (-1100 3325);
DISPLAY INVISIBLE (-1100 3325);
FORCEPROP 1 LAST BODY_TYPE PLUMBING
J 0
(-1100 3375);
DISPLAY 0.872340 (-1100 3375);
PAINT GREEN (-1100 3375);
DISPLAY INVISIBLE (-1100 3375);
FORCEPROP 1 LAST HDL_TAP TRUE
J 0
(-775 3200);
DISPLAY 0.872340 (-775 3200);
DISPLAY INVISIBLE (-775 3200);
FORCEPROP 1 LAST PATH I107
J 0
(-1102 3325);
DISPLAY 0.872340 (-1102 3325);
PAINT GREEN (-1102 3325);
DISPLAY INVISIBLE (-1102 3325);
FORCEADD TAP..1
(-1100 3525);
FORCEPROP 3 LASTPIN (-1150 3525) SIG_NAME M_E_CPU1_SA_DQ<22>
J 0
(-1140 3535);
DISPLAY 0.659574 (-1140 3535);
PAINT MONO (-1140 3535);
DISPLAY INVISIBLE (-1140 3535);
FORCEPROP 1 LASTPIN (-1150 3525) BN 22
J 0
(-1162 3533);
DISPLAY 0.680851 (-1162 3533);
PAINT GREEN (-1162 3533);
FORCEPROP 2 LAST CDS_LIB standard
J 0
(-1100 3525);
DISPLAY INVISIBLE (-1100 3525);
FORCEPROP 1 LAST BODY_TYPE PLUMBING
J 0
(-1100 3575);
DISPLAY 0.872340 (-1100 3575);
PAINT GREEN (-1100 3575);
DISPLAY INVISIBLE (-1100 3575);
FORCEPROP 1 LAST HDL_TAP TRUE
J 0
(-775 3400);
DISPLAY 0.872340 (-775 3400);
DISPLAY INVISIBLE (-775 3400);
FORCEPROP 1 LAST PATH I108
J 0
(-1102 3525);
DISPLAY 0.872340 (-1102 3525);
PAINT GREEN (-1102 3525);
DISPLAY INVISIBLE (-1102 3525);
FORCEADD TAP..1
(-1100 3475);
FORCEPROP 3 LASTPIN (-1150 3475) SIG_NAME M_E_CPU1_SA_DQ<21>
J 0
(-1140 3485);
DISPLAY 0.659574 (-1140 3485);
PAINT MONO (-1140 3485);
DISPLAY INVISIBLE (-1140 3485);
FORCEPROP 1 LASTPIN (-1150 3475) BN 21
J 0
(-1162 3483);
DISPLAY 0.680851 (-1162 3483);
PAINT GREEN (-1162 3483);
FORCEPROP 2 LAST CDS_LIB standard
J 0
(-1100 3475);
PAINT MONO (-1100 3475);
DISPLAY INVISIBLE (-1100 3475);
FORCEPROP 1 LAST BODY_TYPE PLUMBING
J 0
(-1100 3525);
DISPLAY 0.872340 (-1100 3525);
PAINT GREEN (-1100 3525);
DISPLAY INVISIBLE (-1100 3525);
FORCEPROP 1 LAST HDL_TAP TRUE
J 0
(-775 3350);
DISPLAY 0.872340 (-775 3350);
DISPLAY INVISIBLE (-775 3350);
FORCEPROP 1 LAST PATH I109
J 0
(-1102 3475);
DISPLAY 0.872340 (-1102 3475);
PAINT GREEN (-1102 3475);
DISPLAY INVISIBLE (-1102 3475);
FORCEADD OFFPAGE..1
(-3675 1625);
FORCEPROP 2 LAST $XR1 107 
J 0
(-4016 1625);
DISPLAY 0.638298 (-4016 1625);
PAINT MONO (-4016 1625);
FORCEPROP 2 LAST $XR0 55 
J 0
(-3896 1625);
DISPLAY 0.638298 (-3896 1625);
PAINT MONO (-3896 1625);
FORCEPROP 2 LAST CDS_LIB standard
J 0
(-3675 1625);
PAINT MONO (-3675 1625);
DISPLAY INVISIBLE (-3675 1625);
FORCEPROP 1 LAST OFFPAGE TRUE
J 0
(-3350 1500);
DISPLAY 0.872340 (-3350 1500);
DISPLAY INVISIBLE (-3350 1500);
FORCEPROP 1 LAST COMMENT_BODY TRUE
J 0
(-3550 1525);
DISPLAY 0.872340 (-3550 1525);
PAINT GREEN (-3550 1525);
DISPLAY INVISIBLE (-3550 1525);
FORCEPROP 2 LAST PATH I11
J 0
(-3625 1700);
DISPLAY 1.021277 (-3625 1700);
DISPLAY INVISIBLE (-3625 1700);
FORCEADD TAP..1
(-1100 3425);
FORCEPROP 3 LASTPIN (-1150 3425) SIG_NAME M_E_CPU1_SA_DQ<20>
J 0
(-1140 3435);
DISPLAY 0.659574 (-1140 3435);
PAINT MONO (-1140 3435);
DISPLAY INVISIBLE (-1140 3435);
FORCEPROP 1 LASTPIN (-1150 3425) BN 20
J 0
(-1162 3433);
DISPLAY 0.680851 (-1162 3433);
PAINT GREEN (-1162 3433);
FORCEPROP 2 LAST CDS_LIB standard
J 0
(-1100 3425);
PAINT MONO (-1100 3425);
DISPLAY INVISIBLE (-1100 3425);
FORCEPROP 1 LAST BODY_TYPE PLUMBING
J 0
(-1100 3475);
DISPLAY 0.872340 (-1100 3475);
PAINT GREEN (-1100 3475);
DISPLAY INVISIBLE (-1100 3475);
FORCEPROP 1 LAST HDL_TAP TRUE
J 0
(-775 3300);
DISPLAY 0.872340 (-775 3300);
DISPLAY INVISIBLE (-775 3300);
FORCEPROP 1 LAST PATH I110
J 0
(-1102 3425);
DISPLAY 0.872340 (-1102 3425);
PAINT GREEN (-1102 3425);
DISPLAY INVISIBLE (-1102 3425);
FORCEADD TAP..1
(-1100 3625);
FORCEPROP 3 LASTPIN (-1150 3625) SIG_NAME M_E_CPU1_SA_DQ<24>
J 0
(-1140 3635);
DISPLAY 0.659574 (-1140 3635);
PAINT MONO (-1140 3635);
DISPLAY INVISIBLE (-1140 3635);
FORCEPROP 1 LASTPIN (-1150 3625) BN 24
J 0
(-1162 3633);
DISPLAY 0.680851 (-1162 3633);
PAINT GREEN (-1162 3633);
FORCEPROP 2 LAST CDS_LIB standard
J 0
(-1100 3625);
DISPLAY INVISIBLE (-1100 3625);
FORCEPROP 1 LAST BODY_TYPE PLUMBING
J 0
(-1100 3675);
DISPLAY 0.872340 (-1100 3675);
PAINT GREEN (-1100 3675);
DISPLAY INVISIBLE (-1100 3675);
FORCEPROP 1 LAST HDL_TAP TRUE
J 0
(-775 3500);
DISPLAY 0.872340 (-775 3500);
DISPLAY INVISIBLE (-775 3500);
FORCEPROP 1 LAST PATH I111
J 0
(-1102 3625);
DISPLAY 0.872340 (-1102 3625);
PAINT GREEN (-1102 3625);
DISPLAY INVISIBLE (-1102 3625);
FORCEADD TAP..1
(-1100 3575);
FORCEPROP 3 LASTPIN (-1150 3575) SIG_NAME M_E_CPU1_SA_DQ<23>
J 0
(-1140 3585);
DISPLAY 0.659574 (-1140 3585);
PAINT MONO (-1140 3585);
DISPLAY INVISIBLE (-1140 3585);
FORCEPROP 1 LASTPIN (-1150 3575) BN 23
J 0
(-1162 3583);
DISPLAY 0.680851 (-1162 3583);
PAINT GREEN (-1162 3583);
FORCEPROP 2 LAST CDS_LIB standard
J 0
(-1100 3575);
DISPLAY INVISIBLE (-1100 3575);
FORCEPROP 1 LAST BODY_TYPE PLUMBING
J 0
(-1100 3625);
DISPLAY 0.872340 (-1100 3625);
PAINT GREEN (-1100 3625);
DISPLAY INVISIBLE (-1100 3625);
FORCEPROP 1 LAST HDL_TAP TRUE
J 0
(-775 3450);
DISPLAY 0.872340 (-775 3450);
DISPLAY INVISIBLE (-775 3450);
FORCEPROP 1 LAST PATH I112
J 0
(-1102 3575);
DISPLAY 0.872340 (-1102 3575);
PAINT GREEN (-1102 3575);
DISPLAY INVISIBLE (-1102 3575);
FORCEADD TAP..1
(-1100 3775);
FORCEPROP 3 LASTPIN (-1150 3775) SIG_NAME M_E_CPU1_SA_DQ<27>
J 0
(-1140 3785);
DISPLAY 0.659574 (-1140 3785);
PAINT MONO (-1140 3785);
DISPLAY INVISIBLE (-1140 3785);
FORCEPROP 1 LASTPIN (-1150 3775) BN 27
J 0
(-1162 3783);
DISPLAY 0.680851 (-1162 3783);
PAINT GREEN (-1162 3783);
FORCEPROP 2 LAST CDS_LIB standard
J 0
(-1100 3775);
DISPLAY INVISIBLE (-1100 3775);
FORCEPROP 1 LAST BODY_TYPE PLUMBING
J 0
(-1100 3825);
DISPLAY 0.872340 (-1100 3825);
PAINT GREEN (-1100 3825);
DISPLAY INVISIBLE (-1100 3825);
FORCEPROP 1 LAST HDL_TAP TRUE
J 0
(-775 3650);
DISPLAY 0.872340 (-775 3650);
DISPLAY INVISIBLE (-775 3650);
FORCEPROP 1 LAST PATH I113
J 0
(-1102 3775);
DISPLAY 0.872340 (-1102 3775);
PAINT GREEN (-1102 3775);
DISPLAY INVISIBLE (-1102 3775);
FORCEADD TAP..1
(-1100 3725);
FORCEPROP 3 LASTPIN (-1150 3725) SIG_NAME M_E_CPU1_SA_DQ<26>
J 0
(-1140 3735);
DISPLAY 0.659574 (-1140 3735);
PAINT MONO (-1140 3735);
DISPLAY INVISIBLE (-1140 3735);
FORCEPROP 1 LASTPIN (-1150 3725) BN 26
J 0
(-1162 3733);
DISPLAY 0.680851 (-1162 3733);
PAINT GREEN (-1162 3733);
FORCEPROP 2 LAST CDS_LIB standard
J 0
(-1100 3725);
DISPLAY INVISIBLE (-1100 3725);
FORCEPROP 1 LAST BODY_TYPE PLUMBING
J 0
(-1100 3775);
DISPLAY 0.872340 (-1100 3775);
PAINT GREEN (-1100 3775);
DISPLAY INVISIBLE (-1100 3775);
FORCEPROP 1 LAST HDL_TAP TRUE
J 0
(-775 3600);
DISPLAY 0.872340 (-775 3600);
DISPLAY INVISIBLE (-775 3600);
FORCEPROP 1 LAST PATH I114
J 0
(-1102 3725);
DISPLAY 0.872340 (-1102 3725);
PAINT GREEN (-1102 3725);
DISPLAY INVISIBLE (-1102 3725);
FORCEADD TAP..1
(-1100 3675);
FORCEPROP 3 LASTPIN (-1150 3675) SIG_NAME M_E_CPU1_SA_DQ<25>
J 0
(-1140 3685);
DISPLAY 0.659574 (-1140 3685);
PAINT MONO (-1140 3685);
DISPLAY INVISIBLE (-1140 3685);
FORCEPROP 1 LASTPIN (-1150 3675) BN 25
J 0
(-1162 3683);
DISPLAY 0.680851 (-1162 3683);
PAINT GREEN (-1162 3683);
FORCEPROP 2 LAST CDS_LIB standard
J 0
(-1100 3675);
DISPLAY INVISIBLE (-1100 3675);
FORCEPROP 1 LAST BODY_TYPE PLUMBING
J 0
(-1100 3725);
DISPLAY 0.872340 (-1100 3725);
PAINT GREEN (-1100 3725);
DISPLAY INVISIBLE (-1100 3725);
FORCEPROP 1 LAST HDL_TAP TRUE
J 0
(-775 3550);
DISPLAY 0.872340 (-775 3550);
DISPLAY INVISIBLE (-775 3550);
FORCEPROP 1 LAST PATH I115
J 0
(-1102 3675);
DISPLAY 0.872340 (-1102 3675);
PAINT GREEN (-1102 3675);
DISPLAY INVISIBLE (-1102 3675);
FORCEADD TAP..1
(-1100 3875);
FORCEPROP 3 LASTPIN (-1150 3875) SIG_NAME M_E_CPU1_SA_DQ<29>
J 0
(-1140 3885);
DISPLAY 0.659574 (-1140 3885);
PAINT MONO (-1140 3885);
DISPLAY INVISIBLE (-1140 3885);
FORCEPROP 1 LASTPIN (-1150 3875) BN 29
J 0
(-1162 3883);
DISPLAY 0.680851 (-1162 3883);
PAINT GREEN (-1162 3883);
FORCEPROP 2 LAST CDS_LIB standard
J 0
(-1100 3875);
DISPLAY INVISIBLE (-1100 3875);
FORCEPROP 1 LAST BODY_TYPE PLUMBING
J 0
(-1100 3925);
DISPLAY 0.872340 (-1100 3925);
PAINT GREEN (-1100 3925);
DISPLAY INVISIBLE (-1100 3925);
FORCEPROP 1 LAST HDL_TAP TRUE
J 0
(-775 3750);
DISPLAY 0.872340 (-775 3750);
DISPLAY INVISIBLE (-775 3750);
FORCEPROP 1 LAST PATH I116
J 0
(-1102 3875);
DISPLAY 0.872340 (-1102 3875);
PAINT GREEN (-1102 3875);
DISPLAY INVISIBLE (-1102 3875);
FORCEADD TAP..1
(-1100 3825);
FORCEPROP 3 LASTPIN (-1150 3825) SIG_NAME M_E_CPU1_SA_DQ<28>
J 0
(-1140 3835);
DISPLAY 0.659574 (-1140 3835);
PAINT MONO (-1140 3835);
DISPLAY INVISIBLE (-1140 3835);
FORCEPROP 1 LASTPIN (-1150 3825) BN 28
J 0
(-1162 3833);
DISPLAY 0.680851 (-1162 3833);
PAINT GREEN (-1162 3833);
FORCEPROP 2 LAST CDS_LIB standard
J 0
(-1100 3825);
DISPLAY INVISIBLE (-1100 3825);
FORCEPROP 1 LAST BODY_TYPE PLUMBING
J 0
(-1100 3875);
DISPLAY 0.872340 (-1100 3875);
PAINT GREEN (-1100 3875);
DISPLAY INVISIBLE (-1100 3875);
FORCEPROP 1 LAST HDL_TAP TRUE
J 0
(-775 3700);
DISPLAY 0.872340 (-775 3700);
DISPLAY INVISIBLE (-775 3700);
FORCEPROP 1 LAST PATH I117
J 0
(-1102 3825);
DISPLAY 0.872340 (-1102 3825);
PAINT GREEN (-1102 3825);
DISPLAY INVISIBLE (-1102 3825);
FORCEADD TAP..1
(-1100 3925);
FORCEPROP 3 LASTPIN (-1150 3925) SIG_NAME M_E_CPU1_SA_DQ<30>
J 0
(-1140 3935);
DISPLAY 0.659574 (-1140 3935);
PAINT MONO (-1140 3935);
DISPLAY INVISIBLE (-1140 3935);
FORCEPROP 1 LASTPIN (-1150 3925) BN 30
J 0
(-1162 3933);
DISPLAY 0.680851 (-1162 3933);
PAINT GREEN (-1162 3933);
FORCEPROP 2 LAST CDS_LIB standard
J 0
(-1100 3925);
DISPLAY INVISIBLE (-1100 3925);
FORCEPROP 1 LAST BODY_TYPE PLUMBING
J 0
(-1100 3975);
DISPLAY 0.872340 (-1100 3975);
PAINT GREEN (-1100 3975);
DISPLAY INVISIBLE (-1100 3975);
FORCEPROP 1 LAST HDL_TAP TRUE
J 0
(-775 3800);
DISPLAY 0.872340 (-775 3800);
DISPLAY INVISIBLE (-775 3800);
FORCEPROP 1 LAST PATH I118
J 0
(-1102 3925);
DISPLAY 0.872340 (-1102 3925);
PAINT GREEN (-1102 3925);
DISPLAY INVISIBLE (-1102 3925);
FORCEADD TAP..1
(-1100 3975);
FORCEPROP 3 LASTPIN (-1150 3975) SIG_NAME M_E_CPU1_SA_DQ<31>
J 0
(-1140 3985);
DISPLAY 0.659574 (-1140 3985);
PAINT MONO (-1140 3985);
DISPLAY INVISIBLE (-1140 3985);
FORCEPROP 1 LASTPIN (-1150 3975) BN 31
J 0
(-1162 3983);
DISPLAY 0.680851 (-1162 3983);
PAINT GREEN (-1162 3983);
FORCEPROP 2 LAST CDS_LIB standard
J 0
(-1100 3975);
DISPLAY INVISIBLE (-1100 3975);
FORCEPROP 1 LAST BODY_TYPE PLUMBING
J 0
(-1100 4025);
DISPLAY 0.872340 (-1100 4025);
PAINT GREEN (-1100 4025);
DISPLAY INVISIBLE (-1100 4025);
FORCEPROP 1 LAST HDL_TAP TRUE
J 0
(-775 3850);
DISPLAY 0.872340 (-775 3850);
DISPLAY INVISIBLE (-775 3850);
FORCEPROP 1 LAST PATH I119
J 0
(-1102 3975);
DISPLAY 0.872340 (-1102 3975);
PAINT GREEN (-1102 3975);
DISPLAY INVISIBLE (-1102 3975);
FORCEADD VCC_CORE..1
(-3575 1850);
FORCEPROP 3 LASTPIN (-3575 1800) SIG_NAME P3V3_AUX\g
J 0
(-3565 1810);
DISPLAY 0.659574 (-3565 1810);
PAINT MONO (-3565 1810);
DISPLAY INVISIBLE (-3565 1810);
FORCEPROP 1 LAST HDL_POWER P3V3_AUX
J 1
(-3575 1900);
DISPLAY 1.148936 (-3575 1900);
PAINT GREEN (-3575 1900);
FORCEPROP 2 LAST CDS_LIB logical_power
J 0
(-3575 1850);
PAINT MONO (-3575 1850);
DISPLAY INVISIBLE (-3575 1850);
FORCEPROP 1 LAST PATH I12
J 0
(-3525 1875);
DISPLAY 0.872340 (-3525 1875);
PAINT AQUA (-3525 1875);
DISPLAY INVISIBLE (-3525 1875);
FORCEADD UNIVERSAL_GND..1
(625 -275);
FORCEPROP 3 LASTPIN (625 -225) SIG_NAME GND\g
J 0
(635 -215);
DISPLAY 0.659574 (635 -215);
PAINT MONO (635 -215);
DISPLAY INVISIBLE (635 -215);
FORCEPROP 1 LAST PATH I120
J 0
(700 -275);
DISPLAY 0.872340 (700 -275);
PAINT AQUA (700 -275);
DISPLAY INVISIBLE (700 -275);
FORCEPROP 1 LAST HDL_POWER GND
J 1
(650 -350);
DISPLAY 0.872340 (650 -350);
PAINT GREEN (650 -350);
DISPLAY INVISIBLE (650 -350);
FORCEPROP 2 LAST CDS_LIB logical_power
J 0
(625 -275);
PAINT MONO (625 -275);
DISPLAY INVISIBLE (625 -275);
FORCEADD UNIVERSAL_GND..1
(2250 -275);
FORCEPROP 3 LASTPIN (2250 -225) SIG_NAME GND\g
J 0
(2260 -215);
DISPLAY 0.659574 (2260 -215);
PAINT MONO (2260 -215);
DISPLAY INVISIBLE (2260 -215);
FORCEPROP 1 LAST PATH I121
J 0
(2325 -275);
DISPLAY 0.872340 (2325 -275);
PAINT AQUA (2325 -275);
DISPLAY INVISIBLE (2325 -275);
FORCEPROP 1 LAST HDL_POWER GND
J 1
(2275 -350);
DISPLAY 0.872340 (2275 -350);
PAINT GREEN (2275 -350);
DISPLAY INVISIBLE (2275 -350);
FORCEPROP 2 LAST CDS_LIB logical_power
J 0
(2250 -275);
PAINT MONO (2250 -275);
DISPLAY INVISIBLE (2250 -275);
FORCEADD Q_CAP..1
(625 100);
FORCEPROP 1 LAST PART_NUMBER CH5221MEB00
J 0
(675 -50);
DISPLAY 0.978723 (675 -50);
DISPLAY INVISIBLE (675 -50);
FORCEPROP 1 LAST PACK_TYPE C0402
J 0
(675 -100);
DISPLAY 0.978723 (675 -100);
FORCEPROP 1 LAST MATERIAL X6S
J 0
(675 0);
DISPLAY 0.978723 (675 0);
FORCEPROP 1 LAST VOLTAGE 6.3V
J 0
(675 100);
DISPLAY 0.978723 (675 100);
FORCEPROP 1 LAST VALUE 2.2UF
J 0
(675 150);
DISPLAY 0.978723 (675 150);
FORCEPROP 1 LAST TOLERANCE 20%
J 0
(675 50);
DISPLAY 0.978723 (675 50);
FORCEPROP 1 LAST $LOCATION C93
J 0
(675 200);
DISPLAY 0.978723 (675 200);
FORCEPROP 1 LASTPIN (625 200) $PN 1
J 0
(635 180);
DISPLAY 0.787234 (635 180);
FORCEPROP 1 LASTPIN (625 0) $PN 2
J 0
(635 -20);
DISPLAY 0.787234 (635 -20);
FORCEPROP 2 LAST CDS_LIB pure_quanta
J 0
(625 100);
PAINT MONO (625 100);
DISPLAY INVISIBLE (625 100);
FORCEPROP 1 LAST PATH I122
J 0
(675 250);
DISPLAY 0.978723 (675 250);
PAINT WHITE (675 250);
DISPLAY INVISIBLE (675 250);
FORCEPROP 1 LAST $LOCATION C93
J 0
(675 300);
DISPLAY 1.021277 (675 300);
DISPLAY INVISIBLE (675 300);
FORCEPROP 2 LAST CDS_LOCATION C93
J 0
(675 300);
DISPLAY 1.021277 (675 300);
DISPLAY INVISIBLE (675 300);
FORCEPROP 2 LAST $SEC 1
J 0
(675 300);
DISPLAY 0.680851 (675 300);
PAINT MONO (675 300);
DISPLAY INVISIBLE (675 300);
FORCEPROP 2 LAST CDS_SEC 1
J 0
(675 300);
DISPLAY 1.021277 (675 300);
DISPLAY INVISIBLE (675 300);
FORCEADD VCC_CORE..1
(625 425);
FORCEPROP 3 LASTPIN (625 375) SIG_NAME P3V3_AUX\g
J 0
(635 385);
DISPLAY 0.659574 (635 385);
PAINT MONO (635 385);
DISPLAY INVISIBLE (635 385);
FORCEPROP 1 LAST HDL_POWER P3V3_AUX
J 1
(625 475);
DISPLAY 1.148936 (625 475);
PAINT GREEN (625 475);
FORCEPROP 2 LAST CDS_LIB logical_power
J 0
(625 425);
PAINT MONO (625 425);
DISPLAY INVISIBLE (625 425);
FORCEPROP 1 LAST PATH I123
J 0
(675 450);
DISPLAY 0.872340 (675 450);
PAINT AQUA (675 450);
DISPLAY INVISIBLE (675 450);
FORCEADD OFFPAGE..3
(-275 2350);
FORCEPROP 2 LAST $XR1 107 
J 0
(29 2350);
DISPLAY 0.638298 (29 2350);
PAINT MONO (29 2350);
FORCEPROP 2 LAST $XR0 55 
J 0
(-61 2350);
DISPLAY 0.638298 (-61 2350);
PAINT MONO (-61 2350);
FORCEPROP 2 LAST CDS_LIB standard
J 2
(-275 2350);
DISPLAY INVISIBLE (-275 2350);
FORCEPROP 1 LAST OFFPAGE TRUE
J 0
(50 2225);
DISPLAY 0.872340 (50 2225);
DISPLAY INVISIBLE (50 2225);
FORCEPROP 1 LAST COMMENT_BODY TRUE
J 0
(-325 2250);
DISPLAY 0.872340 (-325 2250);
PAINT GREEN (-325 2250);
DISPLAY INVISIBLE (-325 2250);
FORCEPROP 2 LAST PATH I124
J 0
(-75 2425);
DISPLAY 1.021277 (-75 2425);
DISPLAY INVISIBLE (-75 2425);
FORCEADD OFFPAGE..3
(-275 4000);
FORCEPROP 2 LAST $XR1 107 
J 0
(29 4000);
DISPLAY 0.638298 (29 4000);
PAINT MONO (29 4000);
FORCEPROP 2 LAST $XR0 55 
J 0
(-61 4000);
DISPLAY 0.638298 (-61 4000);
PAINT MONO (-61 4000);
FORCEPROP 2 LAST CDS_LIB standard
J 2
(-275 4000);
DISPLAY INVISIBLE (-275 4000);
FORCEPROP 1 LAST OFFPAGE TRUE
J 0
(50 3875);
DISPLAY 0.872340 (50 3875);
DISPLAY INVISIBLE (50 3875);
FORCEPROP 1 LAST COMMENT_BODY TRUE
J 0
(-325 3900);
DISPLAY 0.872340 (-325 3900);
PAINT GREEN (-325 3900);
DISPLAY INVISIBLE (-325 3900);
FORCEPROP 2 LAST PATH I125
J 0
(-75 4075);
DISPLAY 1.021277 (-75 4075);
DISPLAY INVISIBLE (-75 4075);
FORCEADD Q_CAP..1
(1625 100);
FORCEPROP 1 LAST PART_NUMBER CH6103KEA00
J 0
(1675 -50);
DISPLAY 0.978723 (1675 -50);
DISPLAY INVISIBLE (1675 -50);
FORCEPROP 1 LAST PACK_TYPE C0805
J 0
(1675 -100);
DISPLAY 0.978723 (1675 -100);
FORCEPROP 1 LAST TOLERANCE 10%
J 0
(1675 50);
DISPLAY 0.978723 (1675 50);
FORCEPROP 1 LAST VALUE 10UF
J 0
(1675 150);
DISPLAY 0.978723 (1675 150);
FORCEPROP 1 LAST VOLTAGE 16V
J 0
(1675 100);
DISPLAY 0.978723 (1675 100);
FORCEPROP 1 LAST MATERIAL X6S
J 0
(1675 0);
DISPLAY 0.978723 (1675 0);
FORCEPROP 1 LAST $LOCATION C94
J 0
(1675 200);
DISPLAY 0.978723 (1675 200);
FORCEPROP 1 LASTPIN (1625 200) $PN 1
J 0
(1635 180);
DISPLAY 0.787234 (1635 180);
FORCEPROP 1 LASTPIN (1625 0) $PN 2
J 0
(1635 -20);
DISPLAY 0.787234 (1635 -20);
FORCEPROP 2 LAST CDS_LIB pure_quanta
J 0
(1625 100);
PAINT MONO (1625 100);
DISPLAY INVISIBLE (1625 100);
FORCEPROP 1 LAST PATH I127
J 0
(1675 250);
DISPLAY 0.978723 (1675 250);
PAINT WHITE (1675 250);
DISPLAY INVISIBLE (1675 250);
FORCEPROP 1 LAST $LOCATION C94
J 0
(1675 300);
DISPLAY 1.021277 (1675 300);
DISPLAY INVISIBLE (1675 300);
FORCEPROP 2 LAST CDS_LOCATION C94
J 0
(1675 300);
DISPLAY 1.021277 (1675 300);
DISPLAY INVISIBLE (1675 300);
FORCEPROP 2 LAST $SEC 1
J 0
(1675 300);
DISPLAY 0.680851 (1675 300);
PAINT MONO (1675 300);
DISPLAY INVISIBLE (1675 300);
FORCEPROP 2 LAST CDS_SEC 1
J 0
(1675 300);
DISPLAY 1.021277 (1675 300);
DISPLAY INVISIBLE (1675 300);
FORCEADD VCC_CORE..1
(1625 425);
FORCEPROP 3 LASTPIN (1625 375) SIG_NAME P12V_S3_AUX_CPU1_NVDIMM\g
J 0
(1635 385);
DISPLAY 0.659574 (1635 385);
PAINT MONO (1635 385);
DISPLAY INVISIBLE (1635 385);
FORCEPROP 1 LAST HDL_POWER P12V_S3_AUX_CPU1_NVDIMM
J 1
(1625 475);
DISPLAY 1.148936 (1625 475);
PAINT GREEN (1625 475);
FORCEPROP 2 LAST CDS_LIB logical_power
J 0
(1625 425);
PAINT MONO (1625 425);
DISPLAY INVISIBLE (1625 425);
FORCEPROP 1 LAST PATH I128
J 0
(1675 450);
DISPLAY 0.872340 (1675 450);
PAINT AQUA (1675 450);
DISPLAY INVISIBLE (1675 450);
FORCEADD TAP..1
(1825 1975);
FORCEPROP 3 LASTPIN (1775 1975) SIG_NAME M_E_CPU1_SB_DQS_DN<0>
J 0
(1785 1985);
DISPLAY 0.659574 (1785 1985);
PAINT MONO (1785 1985);
DISPLAY INVISIBLE (1785 1985);
FORCEPROP 1 LASTPIN (1775 1975) BN 0
J 0
(1763 1983);
DISPLAY 0.680851 (1763 1983);
PAINT GREEN (1763 1983);
FORCEPROP 2 LAST CDS_LIB standard
J 0
(1825 1975);
PAINT MONO (1825 1975);
DISPLAY INVISIBLE (1825 1975);
FORCEPROP 1 LAST BODY_TYPE PLUMBING
J 0
(1825 2025);
DISPLAY 0.872340 (1825 2025);
PAINT GREEN (1825 2025);
DISPLAY INVISIBLE (1825 2025);
FORCEPROP 1 LAST HDL_TAP TRUE
J 0
(2150 1850);
DISPLAY 0.872340 (2150 1850);
DISPLAY INVISIBLE (2150 1850);
FORCEPROP 1 LAST PATH I129
J 0
(1823 1975);
DISPLAY 0.872340 (1823 1975);
PAINT GREEN (1823 1975);
DISPLAY INVISIBLE (1823 1975);
FORCEADD OFFPAGE..3
R 2
(-3675 2150);
FORCEPROP 2 LAST $XR1 107 
J 0
(-4044 2150);
DISPLAY 0.638298 (-4044 2150);
PAINT MONO (-4044 2150);
FORCEPROP 2 LAST $XR0 55 
J 0
(-3924 2150);
DISPLAY 0.638298 (-3924 2150);
PAINT MONO (-3924 2150);
FORCEPROP 2 LAST CDS_LIB standard
J 0
(-3675 2150);
PAINT MONO (-3675 2150);
DISPLAY INVISIBLE (-3675 2150);
FORCEPROP 1 LAST OFFPAGE TRUE
J 2
(-4000 2025);
DISPLAY 0.872340 (-4000 2025);
DISPLAY INVISIBLE (-4000 2025);
FORCEPROP 1 LAST COMMENT_BODY TRUE
J 2
(-3625 2050);
DISPLAY 0.872340 (-3625 2050);
PAINT GREEN (-3625 2050);
DISPLAY INVISIBLE (-3625 2050);
FORCEPROP 2 LAST PATH I13
J 0
(-3625 2225);
DISPLAY 1.021277 (-3625 2225);
DISPLAY INVISIBLE (-3625 2225);
FORCEADD Q_CAP..1
(2250 100);
FORCEPROP 1 LAST PART_NUMBER CH6103KEA00
J 0
(2300 -50);
DISPLAY 0.978723 (2300 -50);
DISPLAY INVISIBLE (2300 -50);
FORCEPROP 1 LAST VALUE 10UF
J 0
(2300 150);
DISPLAY 0.978723 (2300 150);
FORCEPROP 1 LAST TOLERANCE 10%
J 0
(2300 50);
DISPLAY 0.978723 (2300 50);
FORCEPROP 1 LAST VOLTAGE 16V
J 0
(2300 100);
DISPLAY 0.978723 (2300 100);
FORCEPROP 1 LAST PACK_TYPE C0805
J 0
(2300 -100);
DISPLAY 0.978723 (2300 -100);
FORCEPROP 1 LAST MATERIAL X6S
J 0
(2300 0);
DISPLAY 0.978723 (2300 0);
FORCEPROP 1 LAST $LOCATION C95
J 0
(2300 200);
DISPLAY 0.978723 (2300 200);
FORCEPROP 1 LASTPIN (2250 200) $PN 1
J 0
(2260 180);
DISPLAY 0.787234 (2260 180);
FORCEPROP 1 LASTPIN (2250 0) $PN 2
J 0
(2260 -20);
DISPLAY 0.787234 (2260 -20);
FORCEPROP 2 LAST CDS_LIB pure_quanta
J 0
(2250 100);
PAINT MONO (2250 100);
DISPLAY INVISIBLE (2250 100);
FORCEPROP 1 LAST PATH I130
J 0
(2300 250);
DISPLAY 0.978723 (2300 250);
PAINT WHITE (2300 250);
DISPLAY INVISIBLE (2300 250);
FORCEPROP 1 LAST $LOCATION C95
J 0
(2300 300);
DISPLAY 1.021277 (2300 300);
DISPLAY INVISIBLE (2300 300);
FORCEPROP 2 LAST CDS_LOCATION C95
J 0
(2300 300);
DISPLAY 1.021277 (2300 300);
DISPLAY INVISIBLE (2300 300);
FORCEPROP 2 LAST $SEC 1
J 0
(2300 300);
DISPLAY 0.680851 (2300 300);
PAINT MONO (2300 300);
DISPLAY INVISIBLE (2300 300);
FORCEPROP 2 LAST CDS_SEC 1
J 0
(2300 300);
DISPLAY 1.021277 (2300 300);
DISPLAY INVISIBLE (2300 300);
FORCEADD TAP..1
(1650 2025);
FORCEPROP 3 LASTPIN (1600 2025) SIG_NAME M_E_CPU1_SB_DQS_DP<0>
J 0
(1610 2035);
DISPLAY 0.659574 (1610 2035);
PAINT MONO (1610 2035);
DISPLAY INVISIBLE (1610 2035);
FORCEPROP 1 LASTPIN (1600 2025) BN 0
J 0
(1588 2033);
DISPLAY 0.680851 (1588 2033);
PAINT GREEN (1588 2033);
FORCEPROP 2 LAST CDS_LIB standard
J 0
(1650 2025);
PAINT MONO (1650 2025);
DISPLAY INVISIBLE (1650 2025);
FORCEPROP 1 LAST BODY_TYPE PLUMBING
J 0
(1650 2075);
DISPLAY 0.872340 (1650 2075);
PAINT GREEN (1650 2075);
DISPLAY INVISIBLE (1650 2075);
FORCEPROP 1 LAST HDL_TAP TRUE
J 0
(1975 1900);
DISPLAY 0.872340 (1975 1900);
DISPLAY INVISIBLE (1975 1900);
FORCEPROP 1 LAST PATH I131
J 0
(1648 2025);
DISPLAY 0.872340 (1648 2025);
PAINT GREEN (1648 2025);
DISPLAY INVISIBLE (1648 2025);
FORCEADD TAP..1
(1650 2225);
FORCEPROP 3 LASTPIN (1600 2225) SIG_NAME M_E_CPU1_SB_DQS_DP<2>
J 0
(1610 2235);
DISPLAY 0.659574 (1610 2235);
PAINT MONO (1610 2235);
DISPLAY INVISIBLE (1610 2235);
FORCEPROP 1 LASTPIN (1600 2225) BN 2
J 0
(1588 2233);
DISPLAY 0.680851 (1588 2233);
PAINT GREEN (1588 2233);
FORCEPROP 2 LAST CDS_LIB standard
J 0
(1650 2225);
DISPLAY INVISIBLE (1650 2225);
FORCEPROP 1 LAST BODY_TYPE PLUMBING
J 0
(1650 2275);
DISPLAY 0.872340 (1650 2275);
PAINT GREEN (1650 2275);
DISPLAY INVISIBLE (1650 2275);
FORCEPROP 1 LAST HDL_TAP TRUE
J 0
(1975 2100);
DISPLAY 0.872340 (1975 2100);
DISPLAY INVISIBLE (1975 2100);
FORCEPROP 1 LAST PATH I132
J 0
(1648 2225);
DISPLAY 0.872340 (1648 2225);
PAINT GREEN (1648 2225);
DISPLAY INVISIBLE (1648 2225);
FORCEADD TAP..1
(1650 2125);
FORCEPROP 3 LASTPIN (1600 2125) SIG_NAME M_E_CPU1_SB_DQS_DP<1>
J 0
(1610 2135);
DISPLAY 0.659574 (1610 2135);
PAINT MONO (1610 2135);
DISPLAY INVISIBLE (1610 2135);
FORCEPROP 1 LASTPIN (1600 2125) BN 1
J 0
(1588 2133);
DISPLAY 0.680851 (1588 2133);
PAINT GREEN (1588 2133);
FORCEPROP 2 LAST CDS_LIB standard
J 0
(1650 2125);
DISPLAY INVISIBLE (1650 2125);
FORCEPROP 1 LAST BODY_TYPE PLUMBING
J 0
(1650 2175);
DISPLAY 0.872340 (1650 2175);
PAINT GREEN (1650 2175);
DISPLAY INVISIBLE (1650 2175);
FORCEPROP 1 LAST HDL_TAP TRUE
J 0
(1975 2000);
DISPLAY 0.872340 (1975 2000);
DISPLAY INVISIBLE (1975 2000);
FORCEPROP 1 LAST PATH I133
J 0
(1648 2125);
DISPLAY 0.872340 (1648 2125);
PAINT GREEN (1648 2125);
DISPLAY INVISIBLE (1648 2125);
FORCEADD TAP..1
(1650 2425);
FORCEPROP 3 LASTPIN (1600 2425) SIG_NAME M_E_CPU1_SB_DQS_DP<4>
J 0
(1610 2435);
DISPLAY 0.659574 (1610 2435);
PAINT MONO (1610 2435);
DISPLAY INVISIBLE (1610 2435);
FORCEPROP 1 LASTPIN (1600 2425) BN 4
J 0
(1588 2433);
DISPLAY 0.680851 (1588 2433);
PAINT GREEN (1588 2433);
FORCEPROP 2 LAST CDS_LIB standard
J 0
(1650 2425);
PAINT MONO (1650 2425);
DISPLAY INVISIBLE (1650 2425);
FORCEPROP 1 LAST BODY_TYPE PLUMBING
J 0
(1650 2475);
DISPLAY 0.872340 (1650 2475);
PAINT GREEN (1650 2475);
DISPLAY INVISIBLE (1650 2475);
FORCEPROP 1 LAST HDL_TAP TRUE
J 0
(1975 2300);
DISPLAY 0.872340 (1975 2300);
DISPLAY INVISIBLE (1975 2300);
FORCEPROP 1 LAST PATH I134
J 0
(1648 2425);
DISPLAY 0.872340 (1648 2425);
PAINT GREEN (1648 2425);
DISPLAY INVISIBLE (1648 2425);
FORCEADD TAP..1
(1650 2325);
FORCEPROP 3 LASTPIN (1600 2325) SIG_NAME M_E_CPU1_SB_DQS_DP<3>
J 0
(1610 2335);
DISPLAY 0.659574 (1610 2335);
PAINT MONO (1610 2335);
DISPLAY INVISIBLE (1610 2335);
FORCEPROP 1 LASTPIN (1600 2325) BN 3
J 0
(1588 2333);
DISPLAY 0.680851 (1588 2333);
PAINT GREEN (1588 2333);
FORCEPROP 2 LAST CDS_LIB standard
J 0
(1650 2325);
PAINT MONO (1650 2325);
DISPLAY INVISIBLE (1650 2325);
FORCEPROP 1 LAST BODY_TYPE PLUMBING
J 0
(1650 2375);
DISPLAY 0.872340 (1650 2375);
PAINT GREEN (1650 2375);
DISPLAY INVISIBLE (1650 2375);
FORCEPROP 1 LAST HDL_TAP TRUE
J 0
(1975 2200);
DISPLAY 0.872340 (1975 2200);
DISPLAY INVISIBLE (1975 2200);
FORCEPROP 1 LAST PATH I135
J 0
(1648 2325);
DISPLAY 0.872340 (1648 2325);
PAINT GREEN (1648 2325);
DISPLAY INVISIBLE (1648 2325);
FORCEADD TAP..1
(1825 2075);
FORCEPROP 3 LASTPIN (1775 2075) SIG_NAME M_E_CPU1_SB_DQS_DN<1>
J 0
(1785 2085);
DISPLAY 0.659574 (1785 2085);
PAINT MONO (1785 2085);
DISPLAY INVISIBLE (1785 2085);
FORCEPROP 1 LASTPIN (1775 2075) BN 1
J 0
(1763 2083);
DISPLAY 0.680851 (1763 2083);
PAINT GREEN (1763 2083);
FORCEPROP 2 LAST CDS_LIB standard
J 0
(1825 2075);
DISPLAY INVISIBLE (1825 2075);
FORCEPROP 1 LAST BODY_TYPE PLUMBING
J 0
(1825 2125);
DISPLAY 0.872340 (1825 2125);
PAINT GREEN (1825 2125);
DISPLAY INVISIBLE (1825 2125);
FORCEPROP 1 LAST HDL_TAP TRUE
J 0
(2150 1950);
DISPLAY 0.872340 (2150 1950);
DISPLAY INVISIBLE (2150 1950);
FORCEPROP 1 LAST PATH I136
J 0
(1823 2075);
DISPLAY 0.872340 (1823 2075);
PAINT GREEN (1823 2075);
DISPLAY INVISIBLE (1823 2075);
FORCEADD TAP..1
(1825 2175);
FORCEPROP 3 LASTPIN (1775 2175) SIG_NAME M_E_CPU1_SB_DQS_DN<2>
J 0
(1785 2185);
DISPLAY 0.659574 (1785 2185);
PAINT MONO (1785 2185);
DISPLAY INVISIBLE (1785 2185);
FORCEPROP 1 LASTPIN (1775 2175) BN 2
J 0
(1763 2183);
DISPLAY 0.680851 (1763 2183);
PAINT GREEN (1763 2183);
FORCEPROP 2 LAST CDS_LIB standard
J 0
(1825 2175);
DISPLAY INVISIBLE (1825 2175);
FORCEPROP 1 LAST BODY_TYPE PLUMBING
J 0
(1825 2225);
DISPLAY 0.872340 (1825 2225);
PAINT GREEN (1825 2225);
DISPLAY INVISIBLE (1825 2225);
FORCEPROP 1 LAST HDL_TAP TRUE
J 0
(2150 2050);
DISPLAY 0.872340 (2150 2050);
DISPLAY INVISIBLE (2150 2050);
FORCEPROP 1 LAST PATH I137
J 0
(1823 2175);
DISPLAY 0.872340 (1823 2175);
PAINT GREEN (1823 2175);
DISPLAY INVISIBLE (1823 2175);
FORCEADD TAP..1
(1825 2275);
FORCEPROP 3 LASTPIN (1775 2275) SIG_NAME M_E_CPU1_SB_DQS_DN<3>
J 0
(1785 2285);
DISPLAY 0.659574 (1785 2285);
PAINT MONO (1785 2285);
DISPLAY INVISIBLE (1785 2285);
FORCEPROP 1 LASTPIN (1775 2275) BN 3
J 0
(1763 2283);
DISPLAY 0.680851 (1763 2283);
PAINT GREEN (1763 2283);
FORCEPROP 2 LAST CDS_LIB standard
J 0
(1825 2275);
PAINT MONO (1825 2275);
DISPLAY INVISIBLE (1825 2275);
FORCEPROP 1 LAST BODY_TYPE PLUMBING
J 0
(1825 2325);
DISPLAY 0.872340 (1825 2325);
PAINT GREEN (1825 2325);
DISPLAY INVISIBLE (1825 2325);
FORCEPROP 1 LAST HDL_TAP TRUE
J 0
(2150 2150);
DISPLAY 0.872340 (2150 2150);
DISPLAY INVISIBLE (2150 2150);
FORCEPROP 1 LAST PATH I138
J 0
(1823 2275);
DISPLAY 0.872340 (1823 2275);
PAINT GREEN (1823 2275);
DISPLAY INVISIBLE (1823 2275);
FORCEADD TAP..1
(1825 2375);
FORCEPROP 3 LASTPIN (1775 2375) SIG_NAME M_E_CPU1_SB_DQS_DN<4>
J 0
(1785 2385);
DISPLAY 0.659574 (1785 2385);
PAINT MONO (1785 2385);
DISPLAY INVISIBLE (1785 2385);
FORCEPROP 1 LASTPIN (1775 2375) BN 4
J 0
(1763 2383);
DISPLAY 0.680851 (1763 2383);
PAINT GREEN (1763 2383);
FORCEPROP 2 LAST CDS_LIB standard
J 0
(1825 2375);
PAINT MONO (1825 2375);
DISPLAY INVISIBLE (1825 2375);
FORCEPROP 1 LAST BODY_TYPE PLUMBING
J 0
(1825 2425);
DISPLAY 0.872340 (1825 2425);
PAINT GREEN (1825 2425);
DISPLAY INVISIBLE (1825 2425);
FORCEPROP 1 LAST HDL_TAP TRUE
J 0
(2150 2250);
DISPLAY 0.872340 (2150 2250);
DISPLAY INVISIBLE (2150 2250);
FORCEPROP 1 LAST PATH I139
J 0
(1823 2375);
DISPLAY 0.872340 (1823 2375);
PAINT GREEN (1823 2375);
DISPLAY INVISIBLE (1823 2375);
FORCEADD OFFPAGE..1
(-3675 2725);
FORCEPROP 2 LAST $XR0 55 
J 0
(-3896 2725);
DISPLAY 0.638298 (-3896 2725);
PAINT MONO (-3896 2725);
FORCEPROP 2 LAST CDS_LIB standard
J 0
(-3675 2725);
PAINT MONO (-3675 2725);
DISPLAY INVISIBLE (-3675 2725);
FORCEPROP 1 LAST OFFPAGE TRUE
J 0
(-3350 2600);
DISPLAY 0.872340 (-3350 2600);
DISPLAY INVISIBLE (-3350 2600);
FORCEPROP 1 LAST COMMENT_BODY TRUE
J 0
(-3550 2625);
DISPLAY 0.872340 (-3550 2625);
PAINT GREEN (-3550 2625);
DISPLAY INVISIBLE (-3550 2625);
FORCEPROP 2 LAST PATH I14
J 0
(-3625 2800);
DISPLAY 1.021277 (-3625 2800);
DISPLAY INVISIBLE (-3625 2800);
FORCEADD TAP..1
(1825 2475);
FORCEPROP 3 LASTPIN (1775 2475) SIG_NAME M_E_CPU1_SB_DQS_DN<5>
J 0
(1785 2485);
DISPLAY 0.659574 (1785 2485);
PAINT MONO (1785 2485);
DISPLAY INVISIBLE (1785 2485);
FORCEPROP 1 LASTPIN (1775 2475) BN 5
J 0
(1763 2483);
DISPLAY 0.680851 (1763 2483);
PAINT GREEN (1763 2483);
FORCEPROP 2 LAST CDS_LIB standard
J 0
(1825 2475);
DISPLAY INVISIBLE (1825 2475);
FORCEPROP 1 LAST BODY_TYPE PLUMBING
J 0
(1825 2525);
DISPLAY 0.872340 (1825 2525);
PAINT GREEN (1825 2525);
DISPLAY INVISIBLE (1825 2525);
FORCEPROP 1 LAST HDL_TAP TRUE
J 0
(2150 2350);
DISPLAY 0.872340 (2150 2350);
DISPLAY INVISIBLE (2150 2350);
FORCEPROP 1 LAST PATH I140
J 0
(1823 2475);
DISPLAY 0.872340 (1823 2475);
PAINT GREEN (1823 2475);
DISPLAY INVISIBLE (1823 2475);
FORCEADD TAP..1
(1650 2525);
FORCEPROP 3 LASTPIN (1600 2525) SIG_NAME M_E_CPU1_SB_DQS_DP<5>
J 0
(1610 2535);
DISPLAY 0.659574 (1610 2535);
PAINT MONO (1610 2535);
DISPLAY INVISIBLE (1610 2535);
FORCEPROP 1 LASTPIN (1600 2525) BN 5
J 0
(1588 2533);
DISPLAY 0.680851 (1588 2533);
PAINT GREEN (1588 2533);
FORCEPROP 2 LAST CDS_LIB standard
J 0
(1650 2525);
DISPLAY INVISIBLE (1650 2525);
FORCEPROP 1 LAST BODY_TYPE PLUMBING
J 0
(1650 2575);
DISPLAY 0.872340 (1650 2575);
PAINT GREEN (1650 2575);
DISPLAY INVISIBLE (1650 2575);
FORCEPROP 1 LAST HDL_TAP TRUE
J 0
(1975 2400);
DISPLAY 0.872340 (1975 2400);
DISPLAY INVISIBLE (1975 2400);
FORCEPROP 1 LAST PATH I141
J 0
(1648 2525);
DISPLAY 0.872340 (1648 2525);
PAINT GREEN (1648 2525);
DISPLAY INVISIBLE (1648 2525);
FORCEADD TAP..1
(1650 2725);
FORCEPROP 3 LASTPIN (1600 2725) SIG_NAME M_E_CPU1_SB_DQS_DP<7>
J 0
(1610 2735);
DISPLAY 0.659574 (1610 2735);
PAINT MONO (1610 2735);
DISPLAY INVISIBLE (1610 2735);
FORCEPROP 1 LASTPIN (1600 2725) BN 7
J 0
(1588 2733);
DISPLAY 0.680851 (1588 2733);
PAINT GREEN (1588 2733);
FORCEPROP 2 LAST CDS_LIB standard
J 0
(1650 2725);
DISPLAY INVISIBLE (1650 2725);
FORCEPROP 1 LAST BODY_TYPE PLUMBING
J 0
(1650 2775);
DISPLAY 0.872340 (1650 2775);
PAINT GREEN (1650 2775);
DISPLAY INVISIBLE (1650 2775);
FORCEPROP 1 LAST HDL_TAP TRUE
J 0
(1975 2600);
DISPLAY 0.872340 (1975 2600);
DISPLAY INVISIBLE (1975 2600);
FORCEPROP 1 LAST PATH I142
J 0
(1648 2725);
DISPLAY 0.872340 (1648 2725);
PAINT GREEN (1648 2725);
DISPLAY INVISIBLE (1648 2725);
FORCEADD TAP..1
(1650 2625);
FORCEPROP 3 LASTPIN (1600 2625) SIG_NAME M_E_CPU1_SB_DQS_DP<6>
J 0
(1610 2635);
DISPLAY 0.659574 (1610 2635);
PAINT MONO (1610 2635);
DISPLAY INVISIBLE (1610 2635);
FORCEPROP 1 LASTPIN (1600 2625) BN 6
J 0
(1588 2633);
DISPLAY 0.680851 (1588 2633);
PAINT GREEN (1588 2633);
FORCEPROP 2 LAST CDS_LIB standard
J 0
(1650 2625);
DISPLAY INVISIBLE (1650 2625);
FORCEPROP 1 LAST BODY_TYPE PLUMBING
J 0
(1650 2675);
DISPLAY 0.872340 (1650 2675);
PAINT GREEN (1650 2675);
DISPLAY INVISIBLE (1650 2675);
FORCEPROP 1 LAST HDL_TAP TRUE
J 0
(1975 2500);
DISPLAY 0.872340 (1975 2500);
DISPLAY INVISIBLE (1975 2500);
FORCEPROP 1 LAST PATH I143
J 0
(1648 2625);
DISPLAY 0.872340 (1648 2625);
PAINT GREEN (1648 2625);
DISPLAY INVISIBLE (1648 2625);
FORCEADD TAP..1
(1650 2925);
FORCEPROP 3 LASTPIN (1600 2925) SIG_NAME M_E_CPU1_SB_DQS_DP<9>
J 0
(1610 2935);
DISPLAY 0.659574 (1610 2935);
PAINT MONO (1610 2935);
DISPLAY INVISIBLE (1610 2935);
FORCEPROP 1 LASTPIN (1600 2925) BN 9
J 0
(1588 2933);
DISPLAY 0.680851 (1588 2933);
PAINT GREEN (1588 2933);
FORCEPROP 2 LAST CDS_LIB standard
J 0
(1650 2925);
DISPLAY INVISIBLE (1650 2925);
FORCEPROP 1 LAST BODY_TYPE PLUMBING
J 0
(1650 2975);
DISPLAY 0.872340 (1650 2975);
PAINT GREEN (1650 2975);
DISPLAY INVISIBLE (1650 2975);
FORCEPROP 1 LAST HDL_TAP TRUE
J 0
(1975 2800);
DISPLAY 0.872340 (1975 2800);
DISPLAY INVISIBLE (1975 2800);
FORCEPROP 1 LAST PATH I144
J 0
(1648 2925);
DISPLAY 0.872340 (1648 2925);
PAINT GREEN (1648 2925);
DISPLAY INVISIBLE (1648 2925);
FORCEADD TAP..1
(1650 2825);
FORCEPROP 3 LASTPIN (1600 2825) SIG_NAME M_E_CPU1_SB_DQS_DP<8>
J 0
(1610 2835);
DISPLAY 0.659574 (1610 2835);
PAINT MONO (1610 2835);
DISPLAY INVISIBLE (1610 2835);
FORCEPROP 1 LASTPIN (1600 2825) BN 8
J 0
(1588 2833);
DISPLAY 0.680851 (1588 2833);
PAINT GREEN (1588 2833);
FORCEPROP 2 LAST CDS_LIB standard
J 0
(1650 2825);
DISPLAY INVISIBLE (1650 2825);
FORCEPROP 1 LAST BODY_TYPE PLUMBING
J 0
(1650 2875);
DISPLAY 0.872340 (1650 2875);
PAINT GREEN (1650 2875);
DISPLAY INVISIBLE (1650 2875);
FORCEPROP 1 LAST HDL_TAP TRUE
J 0
(1975 2700);
DISPLAY 0.872340 (1975 2700);
DISPLAY INVISIBLE (1975 2700);
FORCEPROP 1 LAST PATH I145
J 0
(1648 2825);
DISPLAY 0.872340 (1648 2825);
PAINT GREEN (1648 2825);
DISPLAY INVISIBLE (1648 2825);
FORCEADD TAP..1
(1825 2575);
FORCEPROP 3 LASTPIN (1775 2575) SIG_NAME M_E_CPU1_SB_DQS_DN<6>
J 0
(1785 2585);
DISPLAY 0.659574 (1785 2585);
PAINT MONO (1785 2585);
DISPLAY INVISIBLE (1785 2585);
FORCEPROP 1 LASTPIN (1775 2575) BN 6
J 0
(1763 2583);
DISPLAY 0.680851 (1763 2583);
PAINT GREEN (1763 2583);
FORCEPROP 2 LAST CDS_LIB standard
J 0
(1825 2575);
DISPLAY INVISIBLE (1825 2575);
FORCEPROP 1 LAST BODY_TYPE PLUMBING
J 0
(1825 2625);
DISPLAY 0.872340 (1825 2625);
PAINT GREEN (1825 2625);
DISPLAY INVISIBLE (1825 2625);
FORCEPROP 1 LAST HDL_TAP TRUE
J 0
(2150 2450);
DISPLAY 0.872340 (2150 2450);
DISPLAY INVISIBLE (2150 2450);
FORCEPROP 1 LAST PATH I146
J 0
(1823 2575);
DISPLAY 0.872340 (1823 2575);
PAINT GREEN (1823 2575);
DISPLAY INVISIBLE (1823 2575);
FORCEADD TAP..1
(1825 2675);
FORCEPROP 3 LASTPIN (1775 2675) SIG_NAME M_E_CPU1_SB_DQS_DN<7>
J 0
(1785 2685);
DISPLAY 0.659574 (1785 2685);
PAINT MONO (1785 2685);
DISPLAY INVISIBLE (1785 2685);
FORCEPROP 1 LASTPIN (1775 2675) BN 7
J 0
(1763 2683);
DISPLAY 0.680851 (1763 2683);
PAINT GREEN (1763 2683);
FORCEPROP 2 LAST CDS_LIB standard
J 0
(1825 2675);
DISPLAY INVISIBLE (1825 2675);
FORCEPROP 1 LAST BODY_TYPE PLUMBING
J 0
(1825 2725);
DISPLAY 0.872340 (1825 2725);
PAINT GREEN (1825 2725);
DISPLAY INVISIBLE (1825 2725);
FORCEPROP 1 LAST HDL_TAP TRUE
J 0
(2150 2550);
DISPLAY 0.872340 (2150 2550);
DISPLAY INVISIBLE (2150 2550);
FORCEPROP 1 LAST PATH I147
J 0
(1823 2675);
DISPLAY 0.872340 (1823 2675);
PAINT GREEN (1823 2675);
DISPLAY INVISIBLE (1823 2675);
FORCEADD TAP..1
(1825 2875);
FORCEPROP 3 LASTPIN (1775 2875) SIG_NAME M_E_CPU1_SB_DQS_DN<9>
J 0
(1785 2885);
DISPLAY 0.659574 (1785 2885);
PAINT MONO (1785 2885);
DISPLAY INVISIBLE (1785 2885);
FORCEPROP 1 LASTPIN (1775 2875) BN 9
J 0
(1763 2883);
DISPLAY 0.680851 (1763 2883);
PAINT GREEN (1763 2883);
FORCEPROP 2 LAST CDS_LIB standard
J 0
(1825 2875);
DISPLAY INVISIBLE (1825 2875);
FORCEPROP 1 LAST BODY_TYPE PLUMBING
J 0
(1825 2925);
DISPLAY 0.872340 (1825 2925);
PAINT GREEN (1825 2925);
DISPLAY INVISIBLE (1825 2925);
FORCEPROP 1 LAST HDL_TAP TRUE
J 0
(2150 2750);
DISPLAY 0.872340 (2150 2750);
DISPLAY INVISIBLE (2150 2750);
FORCEPROP 1 LAST PATH I148
J 0
(1823 2875);
DISPLAY 0.872340 (1823 2875);
PAINT GREEN (1823 2875);
DISPLAY INVISIBLE (1823 2875);
FORCEADD TAP..1
(1825 2775);
FORCEPROP 3 LASTPIN (1775 2775) SIG_NAME M_E_CPU1_SB_DQS_DN<8>
J 0
(1785 2785);
DISPLAY 0.659574 (1785 2785);
PAINT MONO (1785 2785);
DISPLAY INVISIBLE (1785 2785);
FORCEPROP 1 LASTPIN (1775 2775) BN 8
J 0
(1763 2783);
DISPLAY 0.680851 (1763 2783);
PAINT GREEN (1763 2783);
FORCEPROP 2 LAST CDS_LIB standard
J 0
(1825 2775);
DISPLAY INVISIBLE (1825 2775);
FORCEPROP 1 LAST BODY_TYPE PLUMBING
J 0
(1825 2825);
DISPLAY 0.872340 (1825 2825);
PAINT GREEN (1825 2825);
DISPLAY INVISIBLE (1825 2825);
FORCEPROP 1 LAST HDL_TAP TRUE
J 0
(2150 2650);
DISPLAY 0.872340 (2150 2650);
DISPLAY INVISIBLE (2150 2650);
FORCEPROP 1 LAST PATH I149
J 0
(1823 2775);
DISPLAY 0.872340 (1823 2775);
PAINT GREEN (1823 2775);
DISPLAY INVISIBLE (1823 2775);
FORCEADD OFFPAGE..1
(-3675 2675);
FORCEPROP 2 LAST $XR0 55 
J 0
(-3896 2675);
DISPLAY 0.638298 (-3896 2675);
PAINT MONO (-3896 2675);
FORCEPROP 2 LAST CDS_LIB standard
J 0
(-3675 2675);
PAINT MONO (-3675 2675);
DISPLAY INVISIBLE (-3675 2675);
FORCEPROP 1 LAST OFFPAGE TRUE
J 0
(-3350 2550);
DISPLAY 0.872340 (-3350 2550);
DISPLAY INVISIBLE (-3350 2550);
FORCEPROP 1 LAST COMMENT_BODY TRUE
J 0
(-3550 2575);
DISPLAY 0.872340 (-3550 2575);
PAINT GREEN (-3550 2575);
DISPLAY INVISIBLE (-3550 2575);
FORCEPROP 2 LAST PATH I15
J 0
(-3625 2750);
DISPLAY 1.021277 (-3625 2750);
DISPLAY INVISIBLE (-3625 2750);
FORCEADD TAP..1
(1650 3075);
FORCEPROP 3 LASTPIN (1600 3075) SIG_NAME M_E_CPU1_SA_DQS_DP<0>
J 0
(1610 3085);
DISPLAY 0.659574 (1610 3085);
PAINT MONO (1610 3085);
DISPLAY INVISIBLE (1610 3085);
FORCEPROP 1 LASTPIN (1600 3075) BN 0
J 0
(1588 3083);
DISPLAY 0.680851 (1588 3083);
PAINT GREEN (1588 3083);
FORCEPROP 2 LAST CDS_LIB standard
J 0
(1650 3075);
PAINT MONO (1650 3075);
DISPLAY INVISIBLE (1650 3075);
FORCEPROP 1 LAST BODY_TYPE PLUMBING
J 0
(1650 3125);
DISPLAY 0.872340 (1650 3125);
PAINT GREEN (1650 3125);
DISPLAY INVISIBLE (1650 3125);
FORCEPROP 1 LAST HDL_TAP TRUE
J 0
(1975 2950);
DISPLAY 0.872340 (1975 2950);
DISPLAY INVISIBLE (1975 2950);
FORCEPROP 1 LAST PATH I150
J 0
(1648 3075);
DISPLAY 0.872340 (1648 3075);
PAINT GREEN (1648 3075);
DISPLAY INVISIBLE (1648 3075);
FORCEADD TAP..1
(1650 3175);
FORCEPROP 3 LASTPIN (1600 3175) SIG_NAME M_E_CPU1_SA_DQS_DP<1>
J 0
(1610 3185);
DISPLAY 0.659574 (1610 3185);
PAINT MONO (1610 3185);
DISPLAY INVISIBLE (1610 3185);
FORCEPROP 1 LASTPIN (1600 3175) BN 1
J 0
(1588 3183);
DISPLAY 0.680851 (1588 3183);
PAINT GREEN (1588 3183);
FORCEPROP 2 LAST CDS_LIB standard
J 0
(1650 3175);
DISPLAY INVISIBLE (1650 3175);
FORCEPROP 1 LAST BODY_TYPE PLUMBING
J 0
(1650 3225);
DISPLAY 0.872340 (1650 3225);
PAINT GREEN (1650 3225);
DISPLAY INVISIBLE (1650 3225);
FORCEPROP 1 LAST HDL_TAP TRUE
J 0
(1975 3050);
DISPLAY 0.872340 (1975 3050);
DISPLAY INVISIBLE (1975 3050);
FORCEPROP 1 LAST PATH I151
J 0
(1648 3175);
DISPLAY 0.872340 (1648 3175);
PAINT GREEN (1648 3175);
DISPLAY INVISIBLE (1648 3175);
FORCEADD TAP..1
(1650 3275);
FORCEPROP 3 LASTPIN (1600 3275) SIG_NAME M_E_CPU1_SA_DQS_DP<2>
J 0
(1610 3285);
DISPLAY 0.659574 (1610 3285);
PAINT MONO (1610 3285);
DISPLAY INVISIBLE (1610 3285);
FORCEPROP 1 LASTPIN (1600 3275) BN 2
J 0
(1588 3283);
DISPLAY 0.680851 (1588 3283);
PAINT GREEN (1588 3283);
FORCEPROP 2 LAST CDS_LIB standard
J 0
(1650 3275);
DISPLAY INVISIBLE (1650 3275);
FORCEPROP 1 LAST BODY_TYPE PLUMBING
J 0
(1650 3325);
DISPLAY 0.872340 (1650 3325);
PAINT GREEN (1650 3325);
DISPLAY INVISIBLE (1650 3325);
FORCEPROP 1 LAST HDL_TAP TRUE
J 0
(1975 3150);
DISPLAY 0.872340 (1975 3150);
DISPLAY INVISIBLE (1975 3150);
FORCEPROP 1 LAST PATH I152
J 0
(1648 3275);
DISPLAY 0.872340 (1648 3275);
PAINT GREEN (1648 3275);
DISPLAY INVISIBLE (1648 3275);
FORCEADD TAP..1
(1650 3475);
FORCEPROP 3 LASTPIN (1600 3475) SIG_NAME M_E_CPU1_SA_DQS_DP<4>
J 0
(1610 3485);
DISPLAY 0.659574 (1610 3485);
PAINT MONO (1610 3485);
DISPLAY INVISIBLE (1610 3485);
FORCEPROP 1 LASTPIN (1600 3475) BN 4
J 0
(1588 3483);
DISPLAY 0.680851 (1588 3483);
PAINT GREEN (1588 3483);
FORCEPROP 2 LAST CDS_LIB standard
J 0
(1650 3475);
PAINT MONO (1650 3475);
DISPLAY INVISIBLE (1650 3475);
FORCEPROP 1 LAST BODY_TYPE PLUMBING
J 0
(1650 3525);
DISPLAY 0.872340 (1650 3525);
PAINT GREEN (1650 3525);
DISPLAY INVISIBLE (1650 3525);
FORCEPROP 1 LAST HDL_TAP TRUE
J 0
(1975 3350);
DISPLAY 0.872340 (1975 3350);
DISPLAY INVISIBLE (1975 3350);
FORCEPROP 1 LAST PATH I153
J 0
(1648 3475);
DISPLAY 0.872340 (1648 3475);
PAINT GREEN (1648 3475);
DISPLAY INVISIBLE (1648 3475);
FORCEADD TAP..1
(1650 3375);
FORCEPROP 3 LASTPIN (1600 3375) SIG_NAME M_E_CPU1_SA_DQS_DP<3>
J 0
(1610 3385);
DISPLAY 0.659574 (1610 3385);
PAINT MONO (1610 3385);
DISPLAY INVISIBLE (1610 3385);
FORCEPROP 1 LASTPIN (1600 3375) BN 3
J 0
(1588 3383);
DISPLAY 0.680851 (1588 3383);
PAINT GREEN (1588 3383);
FORCEPROP 2 LAST CDS_LIB standard
J 0
(1650 3375);
PAINT MONO (1650 3375);
DISPLAY INVISIBLE (1650 3375);
FORCEPROP 1 LAST BODY_TYPE PLUMBING
J 0
(1650 3425);
DISPLAY 0.872340 (1650 3425);
PAINT GREEN (1650 3425);
DISPLAY INVISIBLE (1650 3425);
FORCEPROP 1 LAST HDL_TAP TRUE
J 0
(1975 3250);
DISPLAY 0.872340 (1975 3250);
DISPLAY INVISIBLE (1975 3250);
FORCEPROP 1 LAST PATH I154
J 0
(1648 3375);
DISPLAY 0.872340 (1648 3375);
PAINT GREEN (1648 3375);
DISPLAY INVISIBLE (1648 3375);
FORCEADD TAP..1
(1825 3025);
FORCEPROP 3 LASTPIN (1775 3025) SIG_NAME M_E_CPU1_SA_DQS_DN<0>
J 0
(1785 3035);
DISPLAY 0.659574 (1785 3035);
PAINT MONO (1785 3035);
DISPLAY INVISIBLE (1785 3035);
FORCEPROP 1 LASTPIN (1775 3025) BN 0
J 0
(1763 3033);
DISPLAY 0.680851 (1763 3033);
PAINT GREEN (1763 3033);
FORCEPROP 2 LAST CDS_LIB standard
J 0
(1825 3025);
PAINT MONO (1825 3025);
DISPLAY INVISIBLE (1825 3025);
FORCEPROP 1 LAST BODY_TYPE PLUMBING
J 0
(1825 3075);
DISPLAY 0.872340 (1825 3075);
PAINT GREEN (1825 3075);
DISPLAY INVISIBLE (1825 3075);
FORCEPROP 1 LAST HDL_TAP TRUE
J 0
(2150 2900);
DISPLAY 0.872340 (2150 2900);
DISPLAY INVISIBLE (2150 2900);
FORCEPROP 1 LAST PATH I155
J 0
(1823 3025);
DISPLAY 0.872340 (1823 3025);
PAINT GREEN (1823 3025);
DISPLAY INVISIBLE (1823 3025);
FORCEADD TAP..1
(1825 3125);
FORCEPROP 3 LASTPIN (1775 3125) SIG_NAME M_E_CPU1_SA_DQS_DN<1>
J 0
(1785 3135);
DISPLAY 0.659574 (1785 3135);
PAINT MONO (1785 3135);
DISPLAY INVISIBLE (1785 3135);
FORCEPROP 1 LASTPIN (1775 3125) BN 1
J 0
(1763 3133);
DISPLAY 0.680851 (1763 3133);
PAINT GREEN (1763 3133);
FORCEPROP 2 LAST CDS_LIB standard
J 0
(1825 3125);
DISPLAY INVISIBLE (1825 3125);
FORCEPROP 1 LAST BODY_TYPE PLUMBING
J 0
(1825 3175);
DISPLAY 0.872340 (1825 3175);
PAINT GREEN (1825 3175);
DISPLAY INVISIBLE (1825 3175);
FORCEPROP 1 LAST HDL_TAP TRUE
J 0
(2150 3000);
DISPLAY 0.872340 (2150 3000);
DISPLAY INVISIBLE (2150 3000);
FORCEPROP 1 LAST PATH I156
J 0
(1823 3125);
DISPLAY 0.872340 (1823 3125);
PAINT GREEN (1823 3125);
DISPLAY INVISIBLE (1823 3125);
FORCEADD TAP..1
(1825 3225);
FORCEPROP 3 LASTPIN (1775 3225) SIG_NAME M_E_CPU1_SA_DQS_DN<2>
J 0
(1785 3235);
DISPLAY 0.659574 (1785 3235);
PAINT MONO (1785 3235);
DISPLAY INVISIBLE (1785 3235);
FORCEPROP 1 LASTPIN (1775 3225) BN 2
J 0
(1763 3233);
DISPLAY 0.680851 (1763 3233);
PAINT GREEN (1763 3233);
FORCEPROP 2 LAST CDS_LIB standard
J 0
(1825 3225);
DISPLAY INVISIBLE (1825 3225);
FORCEPROP 1 LAST BODY_TYPE PLUMBING
J 0
(1825 3275);
DISPLAY 0.872340 (1825 3275);
PAINT GREEN (1825 3275);
DISPLAY INVISIBLE (1825 3275);
FORCEPROP 1 LAST HDL_TAP TRUE
J 0
(2150 3100);
DISPLAY 0.872340 (2150 3100);
DISPLAY INVISIBLE (2150 3100);
FORCEPROP 1 LAST PATH I157
J 0
(1823 3225);
DISPLAY 0.872340 (1823 3225);
PAINT GREEN (1823 3225);
DISPLAY INVISIBLE (1823 3225);
FORCEADD TAP..1
(1825 3325);
FORCEPROP 3 LASTPIN (1775 3325) SIG_NAME M_E_CPU1_SA_DQS_DN<3>
J 0
(1785 3335);
DISPLAY 0.659574 (1785 3335);
PAINT MONO (1785 3335);
DISPLAY INVISIBLE (1785 3335);
FORCEPROP 1 LASTPIN (1775 3325) BN 3
J 0
(1763 3333);
DISPLAY 0.680851 (1763 3333);
PAINT GREEN (1763 3333);
FORCEPROP 2 LAST CDS_LIB standard
J 0
(1825 3325);
PAINT MONO (1825 3325);
DISPLAY INVISIBLE (1825 3325);
FORCEPROP 1 LAST BODY_TYPE PLUMBING
J 0
(1825 3375);
DISPLAY 0.872340 (1825 3375);
PAINT GREEN (1825 3375);
DISPLAY INVISIBLE (1825 3375);
FORCEPROP 1 LAST HDL_TAP TRUE
J 0
(2150 3200);
DISPLAY 0.872340 (2150 3200);
DISPLAY INVISIBLE (2150 3200);
FORCEPROP 1 LAST PATH I158
J 0
(1823 3325);
DISPLAY 0.872340 (1823 3325);
PAINT GREEN (1823 3325);
DISPLAY INVISIBLE (1823 3325);
FORCEADD TAP..1
(1825 3525);
FORCEPROP 3 LASTPIN (1775 3525) SIG_NAME M_E_CPU1_SA_DQS_DN<5>
J 0
(1785 3535);
DISPLAY 0.659574 (1785 3535);
PAINT MONO (1785 3535);
DISPLAY INVISIBLE (1785 3535);
FORCEPROP 1 LASTPIN (1775 3525) BN 5
J 0
(1763 3533);
DISPLAY 0.680851 (1763 3533);
PAINT GREEN (1763 3533);
FORCEPROP 2 LAST CDS_LIB standard
J 0
(1825 3525);
DISPLAY INVISIBLE (1825 3525);
FORCEPROP 1 LAST BODY_TYPE PLUMBING
J 0
(1825 3575);
DISPLAY 0.872340 (1825 3575);
PAINT GREEN (1825 3575);
DISPLAY INVISIBLE (1825 3575);
FORCEPROP 1 LAST HDL_TAP TRUE
J 0
(2150 3400);
DISPLAY 0.872340 (2150 3400);
DISPLAY INVISIBLE (2150 3400);
FORCEPROP 1 LAST PATH I159
J 0
(1823 3525);
DISPLAY 0.872340 (1823 3525);
PAINT GREEN (1823 3525);
DISPLAY INVISIBLE (1823 3525);
FORCEADD OFFPAGE..3
R 2
(-3675 2600);
FORCEPROP 2 LAST $XR1 107 
J 0
(-4044 2600);
DISPLAY 0.638298 (-4044 2600);
PAINT MONO (-4044 2600);
FORCEPROP 2 LAST $XR0 55 
J 0
(-3924 2600);
DISPLAY 0.638298 (-3924 2600);
PAINT MONO (-3924 2600);
FORCEPROP 2 LAST CDS_LIB standard
J 0
(-3675 2600);
PAINT MONO (-3675 2600);
DISPLAY INVISIBLE (-3675 2600);
FORCEPROP 1 LAST OFFPAGE TRUE
J 2
(-4000 2475);
DISPLAY 0.872340 (-4000 2475);
DISPLAY INVISIBLE (-4000 2475);
FORCEPROP 1 LAST COMMENT_BODY TRUE
J 2
(-3625 2500);
DISPLAY 0.872340 (-3625 2500);
PAINT GREEN (-3625 2500);
DISPLAY INVISIBLE (-3625 2500);
FORCEPROP 2 LAST PATH I16
J 0
(-3625 2675);
DISPLAY 1.021277 (-3625 2675);
DISPLAY INVISIBLE (-3625 2675);
FORCEADD TAP..1
(1825 3425);
FORCEPROP 3 LASTPIN (1775 3425) SIG_NAME M_E_CPU1_SA_DQS_DN<4>
J 0
(1785 3435);
DISPLAY 0.659574 (1785 3435);
PAINT MONO (1785 3435);
DISPLAY INVISIBLE (1785 3435);
FORCEPROP 1 LASTPIN (1775 3425) BN 4
J 0
(1763 3433);
DISPLAY 0.680851 (1763 3433);
PAINT GREEN (1763 3433);
FORCEPROP 2 LAST CDS_LIB standard
J 0
(1825 3425);
PAINT MONO (1825 3425);
DISPLAY INVISIBLE (1825 3425);
FORCEPROP 1 LAST BODY_TYPE PLUMBING
J 0
(1825 3475);
DISPLAY 0.872340 (1825 3475);
PAINT GREEN (1825 3475);
DISPLAY INVISIBLE (1825 3475);
FORCEPROP 1 LAST HDL_TAP TRUE
J 0
(2150 3300);
DISPLAY 0.872340 (2150 3300);
DISPLAY INVISIBLE (2150 3300);
FORCEPROP 1 LAST PATH I160
J 0
(1823 3425);
DISPLAY 0.872340 (1823 3425);
PAINT GREEN (1823 3425);
DISPLAY INVISIBLE (1823 3425);
FORCEADD TAP..1
(1650 3575);
FORCEPROP 3 LASTPIN (1600 3575) SIG_NAME M_E_CPU1_SA_DQS_DP<5>
J 0
(1610 3585);
DISPLAY 0.659574 (1610 3585);
PAINT MONO (1610 3585);
DISPLAY INVISIBLE (1610 3585);
FORCEPROP 1 LASTPIN (1600 3575) BN 5
J 0
(1588 3583);
DISPLAY 0.680851 (1588 3583);
PAINT GREEN (1588 3583);
FORCEPROP 2 LAST CDS_LIB standard
J 0
(1650 3575);
DISPLAY INVISIBLE (1650 3575);
FORCEPROP 1 LAST BODY_TYPE PLUMBING
J 0
(1650 3625);
DISPLAY 0.872340 (1650 3625);
PAINT GREEN (1650 3625);
DISPLAY INVISIBLE (1650 3625);
FORCEPROP 1 LAST HDL_TAP TRUE
J 0
(1975 3450);
DISPLAY 0.872340 (1975 3450);
DISPLAY INVISIBLE (1975 3450);
FORCEPROP 1 LAST PATH I161
J 0
(1648 3575);
DISPLAY 0.872340 (1648 3575);
PAINT GREEN (1648 3575);
DISPLAY INVISIBLE (1648 3575);
FORCEADD TAP..1
(1650 3675);
FORCEPROP 3 LASTPIN (1600 3675) SIG_NAME M_E_CPU1_SA_DQS_DP<6>
J 0
(1610 3685);
DISPLAY 0.659574 (1610 3685);
PAINT MONO (1610 3685);
DISPLAY INVISIBLE (1610 3685);
FORCEPROP 1 LASTPIN (1600 3675) BN 6
J 0
(1588 3683);
DISPLAY 0.680851 (1588 3683);
PAINT GREEN (1588 3683);
FORCEPROP 2 LAST CDS_LIB standard
J 0
(1650 3675);
DISPLAY INVISIBLE (1650 3675);
FORCEPROP 1 LAST BODY_TYPE PLUMBING
J 0
(1650 3725);
DISPLAY 0.872340 (1650 3725);
PAINT GREEN (1650 3725);
DISPLAY INVISIBLE (1650 3725);
FORCEPROP 1 LAST HDL_TAP TRUE
J 0
(1975 3550);
DISPLAY 0.872340 (1975 3550);
DISPLAY INVISIBLE (1975 3550);
FORCEPROP 1 LAST PATH I162
J 0
(1648 3675);
DISPLAY 0.872340 (1648 3675);
PAINT GREEN (1648 3675);
DISPLAY INVISIBLE (1648 3675);
FORCEADD TAP..1
(1650 3775);
FORCEPROP 3 LASTPIN (1600 3775) SIG_NAME M_E_CPU1_SA_DQS_DP<7>
J 0
(1610 3785);
DISPLAY 0.659574 (1610 3785);
PAINT MONO (1610 3785);
DISPLAY INVISIBLE (1610 3785);
FORCEPROP 1 LASTPIN (1600 3775) BN 7
J 0
(1588 3783);
DISPLAY 0.680851 (1588 3783);
PAINT GREEN (1588 3783);
FORCEPROP 2 LAST CDS_LIB standard
J 0
(1650 3775);
DISPLAY INVISIBLE (1650 3775);
FORCEPROP 1 LAST BODY_TYPE PLUMBING
J 0
(1650 3825);
DISPLAY 0.872340 (1650 3825);
PAINT GREEN (1650 3825);
DISPLAY INVISIBLE (1650 3825);
FORCEPROP 1 LAST HDL_TAP TRUE
J 0
(1975 3650);
DISPLAY 0.872340 (1975 3650);
DISPLAY INVISIBLE (1975 3650);
FORCEPROP 1 LAST PATH I163
J 0
(1648 3775);
DISPLAY 0.872340 (1648 3775);
PAINT GREEN (1648 3775);
DISPLAY INVISIBLE (1648 3775);
FORCEADD TAP..1
(1650 3975);
FORCEPROP 3 LASTPIN (1600 3975) SIG_NAME M_E_CPU1_SA_DQS_DP<9>
J 0
(1610 3985);
DISPLAY 0.659574 (1610 3985);
PAINT MONO (1610 3985);
DISPLAY INVISIBLE (1610 3985);
FORCEPROP 1 LASTPIN (1600 3975) BN 9
J 0
(1588 3983);
DISPLAY 0.680851 (1588 3983);
PAINT GREEN (1588 3983);
FORCEPROP 2 LAST CDS_LIB standard
J 0
(1650 3975);
DISPLAY INVISIBLE (1650 3975);
FORCEPROP 1 LAST BODY_TYPE PLUMBING
J 0
(1650 4025);
DISPLAY 0.872340 (1650 4025);
PAINT GREEN (1650 4025);
DISPLAY INVISIBLE (1650 4025);
FORCEPROP 1 LAST HDL_TAP TRUE
J 0
(1975 3850);
DISPLAY 0.872340 (1975 3850);
DISPLAY INVISIBLE (1975 3850);
FORCEPROP 1 LAST PATH I164
J 0
(1648 3975);
DISPLAY 0.872340 (1648 3975);
PAINT GREEN (1648 3975);
DISPLAY INVISIBLE (1648 3975);
FORCEADD TAP..1
(1650 3875);
FORCEPROP 3 LASTPIN (1600 3875) SIG_NAME M_E_CPU1_SA_DQS_DP<8>
J 0
(1610 3885);
DISPLAY 0.659574 (1610 3885);
PAINT MONO (1610 3885);
DISPLAY INVISIBLE (1610 3885);
FORCEPROP 1 LASTPIN (1600 3875) BN 8
J 0
(1588 3883);
DISPLAY 0.680851 (1588 3883);
PAINT GREEN (1588 3883);
FORCEPROP 2 LAST CDS_LIB standard
J 0
(1650 3875);
DISPLAY INVISIBLE (1650 3875);
FORCEPROP 1 LAST BODY_TYPE PLUMBING
J 0
(1650 3925);
DISPLAY 0.872340 (1650 3925);
PAINT GREEN (1650 3925);
DISPLAY INVISIBLE (1650 3925);
FORCEPROP 1 LAST HDL_TAP TRUE
J 0
(1975 3750);
DISPLAY 0.872340 (1975 3750);
DISPLAY INVISIBLE (1975 3750);
FORCEPROP 1 LAST PATH I165
J 0
(1648 3875);
DISPLAY 0.872340 (1648 3875);
PAINT GREEN (1648 3875);
DISPLAY INVISIBLE (1648 3875);
FORCEADD TAP..1
(1825 3625);
FORCEPROP 3 LASTPIN (1775 3625) SIG_NAME M_E_CPU1_SA_DQS_DN<6>
J 0
(1785 3635);
DISPLAY 0.659574 (1785 3635);
PAINT MONO (1785 3635);
DISPLAY INVISIBLE (1785 3635);
FORCEPROP 1 LASTPIN (1775 3625) BN 6
J 0
(1763 3633);
DISPLAY 0.680851 (1763 3633);
PAINT GREEN (1763 3633);
FORCEPROP 2 LAST CDS_LIB standard
J 0
(1825 3625);
DISPLAY INVISIBLE (1825 3625);
FORCEPROP 1 LAST BODY_TYPE PLUMBING
J 0
(1825 3675);
DISPLAY 0.872340 (1825 3675);
PAINT GREEN (1825 3675);
DISPLAY INVISIBLE (1825 3675);
FORCEPROP 1 LAST HDL_TAP TRUE
J 0
(2150 3500);
DISPLAY 0.872340 (2150 3500);
DISPLAY INVISIBLE (2150 3500);
FORCEPROP 1 LAST PATH I166
J 0
(1823 3625);
DISPLAY 0.872340 (1823 3625);
PAINT GREEN (1823 3625);
DISPLAY INVISIBLE (1823 3625);
FORCEADD TAP..1
(1825 3725);
FORCEPROP 3 LASTPIN (1775 3725) SIG_NAME M_E_CPU1_SA_DQS_DN<7>
J 0
(1785 3735);
DISPLAY 0.659574 (1785 3735);
PAINT MONO (1785 3735);
DISPLAY INVISIBLE (1785 3735);
FORCEPROP 1 LASTPIN (1775 3725) BN 7
J 0
(1763 3733);
DISPLAY 0.680851 (1763 3733);
PAINT GREEN (1763 3733);
FORCEPROP 2 LAST CDS_LIB standard
J 0
(1825 3725);
DISPLAY INVISIBLE (1825 3725);
FORCEPROP 1 LAST BODY_TYPE PLUMBING
J 0
(1825 3775);
DISPLAY 0.872340 (1825 3775);
PAINT GREEN (1825 3775);
DISPLAY INVISIBLE (1825 3775);
FORCEPROP 1 LAST HDL_TAP TRUE
J 0
(2150 3600);
DISPLAY 0.872340 (2150 3600);
DISPLAY INVISIBLE (2150 3600);
FORCEPROP 1 LAST PATH I167
J 0
(1823 3725);
DISPLAY 0.872340 (1823 3725);
PAINT GREEN (1823 3725);
DISPLAY INVISIBLE (1823 3725);
FORCEADD TAP..1
(1825 3825);
FORCEPROP 3 LASTPIN (1775 3825) SIG_NAME M_E_CPU1_SA_DQS_DN<8>
J 0
(1785 3835);
DISPLAY 0.659574 (1785 3835);
PAINT MONO (1785 3835);
DISPLAY INVISIBLE (1785 3835);
FORCEPROP 1 LASTPIN (1775 3825) BN 8
J 0
(1763 3833);
DISPLAY 0.680851 (1763 3833);
PAINT GREEN (1763 3833);
FORCEPROP 2 LAST CDS_LIB standard
J 0
(1825 3825);
DISPLAY INVISIBLE (1825 3825);
FORCEPROP 1 LAST BODY_TYPE PLUMBING
J 0
(1825 3875);
DISPLAY 0.872340 (1825 3875);
PAINT GREEN (1825 3875);
DISPLAY INVISIBLE (1825 3875);
FORCEPROP 1 LAST HDL_TAP TRUE
J 0
(2150 3700);
DISPLAY 0.872340 (2150 3700);
DISPLAY INVISIBLE (2150 3700);
FORCEPROP 1 LAST PATH I168
J 0
(1823 3825);
DISPLAY 0.872340 (1823 3825);
PAINT GREEN (1823 3825);
DISPLAY INVISIBLE (1823 3825);
FORCEADD TAP..1
(1825 3925);
FORCEPROP 3 LASTPIN (1775 3925) SIG_NAME M_E_CPU1_SA_DQS_DN<9>
J 0
(1785 3935);
DISPLAY 0.659574 (1785 3935);
PAINT MONO (1785 3935);
DISPLAY INVISIBLE (1785 3935);
FORCEPROP 1 LASTPIN (1775 3925) BN 9
J 0
(1763 3933);
DISPLAY 0.680851 (1763 3933);
PAINT GREEN (1763 3933);
FORCEPROP 2 LAST CDS_LIB standard
J 0
(1825 3925);
DISPLAY INVISIBLE (1825 3925);
FORCEPROP 1 LAST BODY_TYPE PLUMBING
J 0
(1825 3975);
DISPLAY 0.872340 (1825 3975);
PAINT GREEN (1825 3975);
DISPLAY INVISIBLE (1825 3975);
FORCEPROP 1 LAST HDL_TAP TRUE
J 0
(2150 3800);
DISPLAY 0.872340 (2150 3800);
DISPLAY INVISIBLE (2150 3800);
FORCEPROP 1 LAST PATH I169
J 0
(1823 3925);
DISPLAY 0.872340 (1823 3925);
PAINT GREEN (1823 3925);
DISPLAY INVISIBLE (1823 3925);
FORCEADD OFFPAGE..1
(-3675 2875);
FORCEPROP 2 LAST $XR0 55 
J 0
(-3896 2875);
DISPLAY 0.638298 (-3896 2875);
PAINT MONO (-3896 2875);
FORCEPROP 2 LAST CDS_LIB standard
J 0
(-3675 2875);
PAINT MONO (-3675 2875);
DISPLAY INVISIBLE (-3675 2875);
FORCEPROP 1 LAST OFFPAGE TRUE
J 0
(-3350 2750);
DISPLAY 0.872340 (-3350 2750);
DISPLAY INVISIBLE (-3350 2750);
FORCEPROP 1 LAST COMMENT_BODY TRUE
J 0
(-3550 2775);
DISPLAY 0.872340 (-3550 2775);
PAINT GREEN (-3550 2775);
DISPLAY INVISIBLE (-3550 2775);
FORCEPROP 2 LAST PATH I17
J 0
(-3625 2950);
DISPLAY 1.021277 (-3625 2950);
DISPLAY INVISIBLE (-3625 2950);
FORCEADD OFFPAGE..2
(2775 2900);
FORCEPROP 2 LAST $XR1 107 
J 0
(3054 2900);
DISPLAY 0.638298 (3054 2900);
PAINT MONO (3054 2900);
FORCEPROP 2 LAST $XR0 55 
J 0
(2964 2900);
DISPLAY 0.638298 (2964 2900);
PAINT MONO (2964 2900);
FORCEPROP 2 LAST CDS_LIB standard
J 0
(2775 2900);
PAINT MONO (2775 2900);
DISPLAY INVISIBLE (2775 2900);
FORCEPROP 1 LAST OFFPAGE TRUE
J 0
(3100 2775);
DISPLAY 1.170213 (3100 2775);
PAINT GREEN (3100 2775);
DISPLAY INVISIBLE (3100 2775);
FORCEPROP 1 LAST COMMENT_BODY TRUE
J 0
(2730 2805);
DISPLAY 1.170213 (2730 2805);
PAINT GREEN (2730 2805);
DISPLAY INVISIBLE (2730 2805);
FORCEPROP 2 LAST PATH I170
J 0
(2950 2975);
DISPLAY 1.021277 (2950 2975);
DISPLAY INVISIBLE (2950 2975);
FORCEADD OFFPAGE..2
(2775 2950);
FORCEPROP 2 LAST $XR1 107 
J 0
(3054 2950);
DISPLAY 0.638298 (3054 2950);
PAINT MONO (3054 2950);
FORCEPROP 2 LAST $XR0 55 
J 0
(2964 2950);
DISPLAY 0.638298 (2964 2950);
PAINT MONO (2964 2950);
FORCEPROP 2 LAST CDS_LIB standard
J 0
(2775 2950);
PAINT MONO (2775 2950);
DISPLAY INVISIBLE (2775 2950);
FORCEPROP 1 LAST OFFPAGE TRUE
J 0
(3100 2825);
DISPLAY 1.170213 (3100 2825);
PAINT GREEN (3100 2825);
DISPLAY INVISIBLE (3100 2825);
FORCEPROP 1 LAST COMMENT_BODY TRUE
J 0
(2730 2855);
DISPLAY 1.170213 (2730 2855);
PAINT GREEN (2730 2855);
DISPLAY INVISIBLE (2730 2855);
FORCEPROP 2 LAST PATH I171
J 0
(2950 3025);
DISPLAY 1.021277 (2950 3025);
DISPLAY INVISIBLE (2950 3025);
FORCEADD OFFPAGE..2
(2775 4000);
FORCEPROP 2 LAST $XR1 107 
J 0
(3054 4000);
DISPLAY 0.638298 (3054 4000);
PAINT MONO (3054 4000);
FORCEPROP 2 LAST $XR0 55 
J 0
(2964 4000);
DISPLAY 0.638298 (2964 4000);
PAINT MONO (2964 4000);
FORCEPROP 2 LAST CDS_LIB standard
J 0
(2775 4000);
PAINT MONO (2775 4000);
DISPLAY INVISIBLE (2775 4000);
FORCEPROP 1 LAST OFFPAGE TRUE
J 0
(3100 3875);
DISPLAY 1.170213 (3100 3875);
PAINT GREEN (3100 3875);
DISPLAY INVISIBLE (3100 3875);
FORCEPROP 1 LAST COMMENT_BODY TRUE
J 0
(2730 3905);
DISPLAY 1.170213 (2730 3905);
PAINT GREEN (2730 3905);
DISPLAY INVISIBLE (2730 3905);
FORCEPROP 2 LAST PATH I172
J 0
(2950 4075);
DISPLAY 1.021277 (2950 4075);
DISPLAY INVISIBLE (2950 4075);
FORCEADD OFFPAGE..2
(2775 3950);
FORCEPROP 2 LAST $XR1 107 
J 0
(3054 3950);
DISPLAY 0.638298 (3054 3950);
PAINT MONO (3054 3950);
FORCEPROP 2 LAST $XR0 55 
J 0
(2964 3950);
DISPLAY 0.638298 (2964 3950);
PAINT MONO (2964 3950);
FORCEPROP 2 LAST CDS_LIB standard
J 0
(2775 3950);
PAINT MONO (2775 3950);
DISPLAY INVISIBLE (2775 3950);
FORCEPROP 1 LAST OFFPAGE TRUE
J 0
(3100 3825);
DISPLAY 1.170213 (3100 3825);
PAINT GREEN (3100 3825);
DISPLAY INVISIBLE (3100 3825);
FORCEPROP 1 LAST COMMENT_BODY TRUE
J 0
(2730 3855);
DISPLAY 1.170213 (2730 3855);
PAINT GREEN (2730 3855);
DISPLAY INVISIBLE (2730 3855);
FORCEPROP 2 LAST PATH I173
J 0
(2950 4025);
DISPLAY 1.021277 (2950 4025);
DISPLAY INVISIBLE (2950 4025);
FORCEADD UNIVERSAL_GND..1
(3325 275);
FORCEPROP 3 LASTPIN (3325 325) SIG_NAME GND\g
J 0
(3335 335);
DISPLAY 0.659574 (3335 335);
PAINT MONO (3335 335);
DISPLAY INVISIBLE (3335 335);
FORCEPROP 1 LAST PATH I174
J 0
(3400 275);
DISPLAY 0.872340 (3400 275);
PAINT AQUA (3400 275);
DISPLAY INVISIBLE (3400 275);
FORCEPROP 1 LAST HDL_POWER GND
J 1
(3350 200);
DISPLAY 0.872340 (3350 200);
PAINT GREEN (3350 200);
DISPLAY INVISIBLE (3350 200);
FORCEPROP 2 LAST CDS_LIB logical_power
J 0
(3325 275);
PAINT MONO (3325 275);
DISPLAY INVISIBLE (3325 275);
FORCEADD UNIVERSAL_GND..1
(5025 275);
FORCEPROP 3 LASTPIN (5025 325) SIG_NAME GND\g
J 0
(5035 335);
DISPLAY 0.659574 (5035 335);
PAINT MONO (5035 335);
DISPLAY INVISIBLE (5035 335);
FORCEPROP 1 LAST PATH I176
J 0
(5100 275);
DISPLAY 0.872340 (5100 275);
PAINT AQUA (5100 275);
DISPLAY INVISIBLE (5100 275);
FORCEPROP 1 LAST HDL_POWER GND
J 1
(5050 200);
DISPLAY 0.872340 (5050 200);
PAINT GREEN (5050 200);
DISPLAY INVISIBLE (5050 200);
FORCEPROP 2 LAST CDS_LIB logical_power
J 0
(5025 275);
PAINT MONO (5025 275);
DISPLAY INVISIBLE (5025 275);
FORCEADD VCC_CORE..1
(3325 4525);
FORCEPROP 3 LASTPIN (3325 4475) SIG_NAME P12V_S3_AUX_CPU1_NVDIMM\g
J 0
(3335 4485);
DISPLAY 0.659574 (3335 4485);
PAINT MONO (3335 4485);
DISPLAY INVISIBLE (3335 4485);
FORCEPROP 1 LAST HDL_POWER P12V_S3_AUX_CPU1_NVDIMM
J 1
(3325 4575);
DISPLAY 1.148936 (3325 4575);
PAINT GREEN (3325 4575);
FORCEPROP 2 LAST CDS_LIB logical_power
J 0
(3325 4525);
PAINT MONO (3325 4525);
DISPLAY INVISIBLE (3325 4525);
FORCEPROP 1 LAST PATH I177
J 0
(3375 4550);
DISPLAY 0.872340 (3375 4550);
PAINT AQUA (3375 4550);
DISPLAY INVISIBLE (3375 4550);
FORCEADD SCONN288_ADR50017P130CC..3
(4175 2350);
FORCEPROP 1 LAST PART_NUMBER DFHST8FS461
J 0
(3720 4274);
DISPLAY 0.723404 (3720 4274);
PAINT GREEN (3720 4274);
DISPLAY INVISIBLE (3720 4274);
FORCEPROP 2 LAST PART_TYPE SMLF
J 0
(3725 4425);
DISPLAY 1.021277 (3725 4425);
FORCEPROP 2 LAST VALUE SCONN288_ADR50017-P130CC
J 0
(3725 4375);
DISPLAY 1.021277 (3725 4375);
FORCEPROP 1 LAST MATERIAL IO
J 0
(3720 4147);
DISPLAY 0.723404 (3720 4147);
PAINT GREEN (3720 4147);
FORCEPROP 1 LAST $LOCATION J25
J 0
(3725 4325);
DISPLAY 0.723404 (3725 4325);
PAINT GREEN (3725 4325);
FORCEPROP 0 LASTPIN (4775 725) $PN G1
J 0
(4785 735);
DISPLAY 0.680851 (4785 735);
PAINT MONO (4785 735);
FORCEPROP 0 LASTPIN (4775 675) $PN G2
J 0
(4785 685);
DISPLAY 0.680851 (4785 685);
PAINT MONO (4785 685);
FORCEPROP 0 LASTPIN (4775 625) $PN G3
J 0
(4785 635);
DISPLAY 0.680851 (4785 635);
PAINT MONO (4785 635);
FORCEPROP 0 LASTPIN (3575 3875) $PN 1
J 2
(3565 3885);
DISPLAY 0.680851 (3565 3885);
PAINT MONO (3565 3885);
FORCEPROP 0 LASTPIN (3575 3925) $PN 145
J 2
(3565 3935);
DISPLAY 0.680851 (3565 3935);
PAINT MONO (3565 3935);
FORCEPROP 0 LASTPIN (3575 3975) $PN 146
J 2
(3565 3985);
DISPLAY 0.680851 (3565 3985);
PAINT MONO (3565 3985);
FORCEPROP 0 LASTPIN (4775 825) $PN 6
J 0
(4785 835);
DISPLAY 0.680851 (4785 835);
PAINT MONO (4785 835);
FORCEPROP 0 LASTPIN (4775 875) $PN 8
J 0
(4785 885);
DISPLAY 0.680851 (4785 885);
PAINT MONO (4785 885);
FORCEPROP 0 LASTPIN (4775 925) $PN 10
J 0
(4785 935);
DISPLAY 0.680851 (4785 935);
PAINT MONO (4785 935);
FORCEPROP 0 LASTPIN (4775 975) $PN 13
J 0
(4785 985);
DISPLAY 0.680851 (4785 985);
PAINT MONO (4785 985);
FORCEPROP 0 LASTPIN (4775 1025) $PN 15
J 0
(4785 1035);
DISPLAY 0.680851 (4785 1035);
PAINT MONO (4785 1035);
FORCEPROP 0 LASTPIN (4775 1075) $PN 17
J 0
(4785 1085);
DISPLAY 0.680851 (4785 1085);
PAINT MONO (4785 1085);
FORCEPROP 0 LASTPIN (4775 1125) $PN 19
J 0
(4785 1135);
DISPLAY 0.680851 (4785 1135);
PAINT MONO (4785 1135);
FORCEPROP 0 LASTPIN (4775 1175) $PN 21
J 0
(4785 1185);
DISPLAY 0.680851 (4785 1185);
PAINT MONO (4785 1185);
FORCEPROP 0 LASTPIN (4775 1225) $PN 24
J 0
(4785 1235);
DISPLAY 0.680851 (4785 1235);
PAINT MONO (4785 1235);
FORCEPROP 0 LASTPIN (4775 1275) $PN 26
J 0
(4785 1285);
DISPLAY 0.680851 (4785 1285);
PAINT MONO (4785 1285);
FORCEPROP 0 LASTPIN (4775 1325) $PN 28
J 0
(4785 1335);
DISPLAY 0.680851 (4785 1335);
PAINT MONO (4785 1335);
FORCEPROP 0 LASTPIN (4775 1375) $PN 30
J 0
(4785 1385);
DISPLAY 0.680851 (4785 1385);
PAINT MONO (4785 1385);
FORCEPROP 0 LASTPIN (4775 1425) $PN 32
J 0
(4785 1435);
DISPLAY 0.680851 (4785 1435);
PAINT MONO (4785 1435);
FORCEPROP 0 LASTPIN (4775 1475) $PN 35
J 0
(4785 1485);
DISPLAY 0.680851 (4785 1485);
PAINT MONO (4785 1485);
FORCEPROP 0 LASTPIN (4775 1525) $PN 37
J 0
(4785 1535);
DISPLAY 0.680851 (4785 1535);
PAINT MONO (4785 1535);
FORCEPROP 0 LASTPIN (4775 1575) $PN 39
J 0
(4785 1585);
DISPLAY 0.680851 (4785 1585);
PAINT MONO (4785 1585);
FORCEPROP 0 LASTPIN (4775 1625) $PN 41
J 0
(4785 1635);
DISPLAY 0.680851 (4785 1635);
PAINT MONO (4785 1635);
FORCEPROP 0 LASTPIN (4775 1675) $PN 43
J 0
(4785 1685);
DISPLAY 0.680851 (4785 1685);
PAINT MONO (4785 1685);
FORCEPROP 0 LASTPIN (4775 1725) $PN 46
J 0
(4785 1735);
DISPLAY 0.680851 (4785 1735);
PAINT MONO (4785 1735);
FORCEPROP 0 LASTPIN (4775 1775) $PN 48
J 0
(4785 1785);
DISPLAY 0.680851 (4785 1785);
PAINT MONO (4785 1785);
FORCEPROP 0 LASTPIN (4775 1825) $PN 50
J 0
(4785 1835);
DISPLAY 0.680851 (4785 1835);
PAINT MONO (4785 1835);
FORCEPROP 0 LASTPIN (4775 1875) $PN 52
J 0
(4785 1885);
DISPLAY 0.680851 (4785 1885);
PAINT MONO (4785 1885);
FORCEPROP 0 LASTPIN (4775 1925) $PN 54
J 0
(4785 1935);
DISPLAY 0.680851 (4785 1935);
PAINT MONO (4785 1935);
FORCEPROP 0 LASTPIN (4775 1975) $PN 57
J 0
(4785 1985);
DISPLAY 0.680851 (4785 1985);
PAINT MONO (4785 1985);
FORCEPROP 0 LASTPIN (4775 2025) $PN 59
J 0
(4785 2035);
DISPLAY 0.680851 (4785 2035);
PAINT MONO (4785 2035);
FORCEPROP 0 LASTPIN (4775 2075) $PN 61
J 0
(4785 2085);
DISPLAY 0.680851 (4785 2085);
PAINT MONO (4785 2085);
FORCEPROP 0 LASTPIN (4775 2125) $PN 63
J 0
(4785 2135);
DISPLAY 0.680851 (4785 2135);
PAINT MONO (4785 2135);
FORCEPROP 0 LASTPIN (4775 2175) $PN 65
J 0
(4785 2185);
DISPLAY 0.680851 (4785 2185);
PAINT MONO (4785 2185);
FORCEPROP 0 LASTPIN (4775 2225) $PN 67
J 0
(4785 2235);
DISPLAY 0.680851 (4785 2235);
PAINT MONO (4785 2235);
FORCEPROP 0 LASTPIN (4775 2275) $PN 69
J 0
(4785 2285);
DISPLAY 0.680851 (4785 2285);
PAINT MONO (4785 2285);
FORCEPROP 0 LASTPIN (4775 2325) $PN 71
J 0
(4785 2335);
DISPLAY 0.680851 (4785 2335);
PAINT MONO (4785 2335);
FORCEPROP 0 LASTPIN (4775 2375) $PN 73
J 0
(4785 2385);
DISPLAY 0.680851 (4785 2385);
PAINT MONO (4785 2385);
FORCEPROP 0 LASTPIN (4775 2425) $PN 75
J 0
(4785 2435);
DISPLAY 0.680851 (4785 2435);
PAINT MONO (4785 2435);
FORCEPROP 0 LASTPIN (4775 2475) $PN 77
J 0
(4785 2485);
DISPLAY 0.680851 (4785 2485);
PAINT MONO (4785 2485);
FORCEPROP 0 LASTPIN (4775 2525) $PN 79
J 0
(4785 2535);
DISPLAY 0.680851 (4785 2535);
PAINT MONO (4785 2535);
FORCEPROP 0 LASTPIN (4775 2575) $PN 81
J 0
(4785 2585);
DISPLAY 0.680851 (4785 2585);
PAINT MONO (4785 2585);
FORCEPROP 0 LASTPIN (4775 2625) $PN 83
J 0
(4785 2635);
DISPLAY 0.680851 (4785 2635);
PAINT MONO (4785 2635);
FORCEPROP 0 LASTPIN (4775 2675) $PN 85
J 0
(4785 2685);
DISPLAY 0.680851 (4785 2685);
PAINT MONO (4785 2685);
FORCEPROP 0 LASTPIN (4775 2725) $PN 88
J 0
(4785 2735);
DISPLAY 0.680851 (4785 2735);
PAINT MONO (4785 2735);
FORCEPROP 0 LASTPIN (4775 2775) $PN 90
J 0
(4785 2785);
DISPLAY 0.680851 (4785 2785);
PAINT MONO (4785 2785);
FORCEPROP 0 LASTPIN (4775 2825) $PN 92
J 0
(4785 2835);
DISPLAY 0.680851 (4785 2835);
PAINT MONO (4785 2835);
FORCEPROP 0 LASTPIN (4775 2875) $PN 95
J 0
(4785 2885);
DISPLAY 0.680851 (4785 2885);
PAINT MONO (4785 2885);
FORCEPROP 0 LASTPIN (4775 2925) $PN 97
J 0
(4785 2935);
DISPLAY 0.680851 (4785 2935);
PAINT MONO (4785 2935);
FORCEPROP 0 LASTPIN (4775 2975) $PN 99
J 0
(4785 2985);
DISPLAY 0.680851 (4785 2985);
PAINT MONO (4785 2985);
FORCEPROP 0 LASTPIN (4775 3025) $PN 101
J 0
(4785 3035);
DISPLAY 0.680851 (4785 3035);
PAINT MONO (4785 3035);
FORCEPROP 0 LASTPIN (4775 3075) $PN 103
J 0
(4785 3085);
DISPLAY 0.680851 (4785 3085);
PAINT MONO (4785 3085);
FORCEPROP 0 LASTPIN (4775 3125) $PN 106
J 0
(4785 3135);
DISPLAY 0.680851 (4785 3135);
PAINT MONO (4785 3135);
FORCEPROP 0 LASTPIN (4775 3175) $PN 108
J 0
(4785 3185);
DISPLAY 0.680851 (4785 3185);
PAINT MONO (4785 3185);
FORCEPROP 0 LASTPIN (4775 3225) $PN 110
J 0
(4785 3235);
DISPLAY 0.680851 (4785 3235);
PAINT MONO (4785 3235);
FORCEPROP 0 LASTPIN (4775 3275) $PN 112
J 0
(4785 3285);
DISPLAY 0.680851 (4785 3285);
PAINT MONO (4785 3285);
FORCEPROP 0 LASTPIN (4775 3325) $PN 114
J 0
(4785 3335);
DISPLAY 0.680851 (4785 3335);
PAINT MONO (4785 3335);
FORCEPROP 0 LASTPIN (4775 3375) $PN 117
J 0
(4785 3385);
DISPLAY 0.680851 (4785 3385);
PAINT MONO (4785 3385);
FORCEPROP 0 LASTPIN (4775 3425) $PN 119
J 0
(4785 3435);
DISPLAY 0.680851 (4785 3435);
PAINT MONO (4785 3435);
FORCEPROP 0 LASTPIN (4775 3475) $PN 121
J 0
(4785 3485);
DISPLAY 0.680851 (4785 3485);
PAINT MONO (4785 3485);
FORCEPROP 0 LASTPIN (4775 3525) $PN 123
J 0
(4785 3535);
DISPLAY 0.680851 (4785 3535);
PAINT MONO (4785 3535);
FORCEPROP 0 LASTPIN (4775 3575) $PN 125
J 0
(4785 3585);
DISPLAY 0.680851 (4785 3585);
PAINT MONO (4785 3585);
FORCEPROP 0 LASTPIN (4775 3625) $PN 128
J 0
(4785 3635);
DISPLAY 0.680851 (4785 3635);
PAINT MONO (4785 3635);
FORCEPROP 0 LASTPIN (4775 3675) $PN 130
J 0
(4785 3685);
DISPLAY 0.680851 (4785 3685);
PAINT MONO (4785 3685);
FORCEPROP 0 LASTPIN (4775 3725) $PN 132
J 0
(4785 3735);
DISPLAY 0.680851 (4785 3735);
PAINT MONO (4785 3735);
FORCEPROP 0 LASTPIN (4775 3775) $PN 134
J 0
(4785 3785);
DISPLAY 0.680851 (4785 3785);
PAINT MONO (4785 3785);
FORCEPROP 0 LASTPIN (4775 3825) $PN 136
J 0
(4785 3835);
DISPLAY 0.680851 (4785 3835);
PAINT MONO (4785 3835);
FORCEPROP 0 LASTPIN (4775 3875) $PN 139
J 0
(4785 3885);
DISPLAY 0.680851 (4785 3885);
PAINT MONO (4785 3885);
FORCEPROP 0 LASTPIN (4775 3925) $PN 141
J 0
(4785 3935);
DISPLAY 0.680851 (4785 3935);
PAINT MONO (4785 3935);
FORCEPROP 0 LASTPIN (4775 3975) $PN 143
J 0
(4785 3985);
DISPLAY 0.680851 (4785 3985);
PAINT MONO (4785 3985);
FORCEPROP 0 LASTPIN (3575 725) $PN 151
J 2
(3565 735);
DISPLAY 0.680851 (3565 735);
PAINT MONO (3565 735);
FORCEPROP 0 LASTPIN (3575 775) $PN 153
J 2
(3565 785);
DISPLAY 0.680851 (3565 785);
PAINT MONO (3565 785);
FORCEPROP 0 LASTPIN (3575 825) $PN 155
J 2
(3565 835);
DISPLAY 0.680851 (3565 835);
PAINT MONO (3565 835);
FORCEPROP 0 LASTPIN (3575 875) $PN 158
J 2
(3565 885);
DISPLAY 0.680851 (3565 885);
PAINT MONO (3565 885);
FORCEPROP 0 LASTPIN (3575 925) $PN 160
J 2
(3565 935);
DISPLAY 0.680851 (3565 935);
PAINT MONO (3565 935);
FORCEPROP 0 LASTPIN (3575 975) $PN 162
J 2
(3565 985);
DISPLAY 0.680851 (3565 985);
PAINT MONO (3565 985);
FORCEPROP 0 LASTPIN (3575 1025) $PN 164
J 2
(3565 1035);
DISPLAY 0.680851 (3565 1035);
PAINT MONO (3565 1035);
FORCEPROP 0 LASTPIN (3575 1075) $PN 166
J 2
(3565 1085);
DISPLAY 0.680851 (3565 1085);
PAINT MONO (3565 1085);
FORCEPROP 0 LASTPIN (3575 1125) $PN 169
J 2
(3565 1135);
DISPLAY 0.680851 (3565 1135);
PAINT MONO (3565 1135);
FORCEPROP 0 LASTPIN (3575 1175) $PN 171
J 2
(3565 1185);
DISPLAY 0.680851 (3565 1185);
PAINT MONO (3565 1185);
FORCEPROP 0 LASTPIN (3575 1225) $PN 173
J 2
(3565 1235);
DISPLAY 0.680851 (3565 1235);
PAINT MONO (3565 1235);
FORCEPROP 0 LASTPIN (3575 1275) $PN 175
J 2
(3565 1285);
DISPLAY 0.680851 (3565 1285);
PAINT MONO (3565 1285);
FORCEPROP 0 LASTPIN (3575 1325) $PN 177
J 2
(3565 1335);
DISPLAY 0.680851 (3565 1335);
PAINT MONO (3565 1335);
FORCEPROP 0 LASTPIN (3575 1375) $PN 180
J 2
(3565 1385);
DISPLAY 0.680851 (3565 1385);
PAINT MONO (3565 1385);
FORCEPROP 0 LASTPIN (3575 1425) $PN 182
J 2
(3565 1435);
DISPLAY 0.680851 (3565 1435);
PAINT MONO (3565 1435);
FORCEPROP 0 LASTPIN (3575 1475) $PN 184
J 2
(3565 1485);
DISPLAY 0.680851 (3565 1485);
PAINT MONO (3565 1485);
FORCEPROP 0 LASTPIN (3575 1525) $PN 186
J 2
(3565 1535);
DISPLAY 0.680851 (3565 1535);
PAINT MONO (3565 1535);
FORCEPROP 0 LASTPIN (3575 1575) $PN 188
J 2
(3565 1585);
DISPLAY 0.680851 (3565 1585);
PAINT MONO (3565 1585);
FORCEPROP 0 LASTPIN (3575 1625) $PN 191
J 2
(3565 1635);
DISPLAY 0.680851 (3565 1635);
PAINT MONO (3565 1635);
FORCEPROP 0 LASTPIN (3575 1675) $PN 193
J 2
(3565 1685);
DISPLAY 0.680851 (3565 1685);
PAINT MONO (3565 1685);
FORCEPROP 0 LASTPIN (3575 1725) $PN 195
J 2
(3565 1735);
DISPLAY 0.680851 (3565 1735);
PAINT MONO (3565 1735);
FORCEPROP 0 LASTPIN (3575 1775) $PN 197
J 2
(3565 1785);
DISPLAY 0.680851 (3565 1785);
PAINT MONO (3565 1785);
FORCEPROP 0 LASTPIN (3575 1825) $PN 199
J 2
(3565 1835);
DISPLAY 0.680851 (3565 1835);
PAINT MONO (3565 1835);
FORCEPROP 0 LASTPIN (3575 1875) $PN 202
J 2
(3565 1885);
DISPLAY 0.680851 (3565 1885);
PAINT MONO (3565 1885);
FORCEPROP 0 LASTPIN (3575 1925) $PN 204
J 2
(3565 1935);
DISPLAY 0.680851 (3565 1935);
PAINT MONO (3565 1935);
FORCEPROP 0 LASTPIN (3575 1975) $PN 206
J 2
(3565 1985);
DISPLAY 0.680851 (3565 1985);
PAINT MONO (3565 1985);
FORCEPROP 0 LASTPIN (3575 2025) $PN 208
J 2
(3565 2035);
DISPLAY 0.680851 (3565 2035);
PAINT MONO (3565 2035);
FORCEPROP 0 LASTPIN (3575 2075) $PN 210
J 2
(3565 2085);
DISPLAY 0.680851 (3565 2085);
PAINT MONO (3565 2085);
FORCEPROP 0 LASTPIN (3575 2125) $PN 212
J 2
(3565 2135);
DISPLAY 0.680851 (3565 2135);
PAINT MONO (3565 2135);
FORCEPROP 0 LASTPIN (3575 2175) $PN 214
J 2
(3565 2185);
DISPLAY 0.680851 (3565 2185);
PAINT MONO (3565 2185);
FORCEPROP 0 LASTPIN (3575 2225) $PN 216
J 2
(3565 2235);
DISPLAY 0.680851 (3565 2235);
PAINT MONO (3565 2235);
FORCEPROP 0 LASTPIN (3575 2275) $PN 219
J 2
(3565 2285);
DISPLAY 0.680851 (3565 2285);
PAINT MONO (3565 2285);
FORCEPROP 0 LASTPIN (3575 2325) $PN 222
J 2
(3565 2335);
DISPLAY 0.680851 (3565 2335);
PAINT MONO (3565 2335);
FORCEPROP 0 LASTPIN (3575 2375) $PN 224
J 2
(3565 2385);
DISPLAY 0.680851 (3565 2385);
PAINT MONO (3565 2385);
FORCEPROP 0 LASTPIN (3575 2425) $PN 226
J 2
(3565 2435);
DISPLAY 0.680851 (3565 2435);
PAINT MONO (3565 2435);
FORCEPROP 0 LASTPIN (3575 2475) $PN 228
J 2
(3565 2485);
DISPLAY 0.680851 (3565 2485);
PAINT MONO (3565 2485);
FORCEPROP 0 LASTPIN (3575 2525) $PN 230
J 2
(3565 2535);
DISPLAY 0.680851 (3565 2535);
PAINT MONO (3565 2535);
FORCEPROP 0 LASTPIN (3575 2575) $PN 233
J 2
(3565 2585);
DISPLAY 0.680851 (3565 2585);
PAINT MONO (3565 2585);
FORCEPROP 0 LASTPIN (3575 2625) $PN 235
J 2
(3565 2635);
DISPLAY 0.680851 (3565 2635);
PAINT MONO (3565 2635);
FORCEPROP 0 LASTPIN (3575 2675) $PN 237
J 2
(3565 2685);
DISPLAY 0.680851 (3565 2685);
PAINT MONO (3565 2685);
FORCEPROP 0 LASTPIN (3575 2725) $PN 240
J 2
(3565 2735);
DISPLAY 0.680851 (3565 2735);
PAINT MONO (3565 2735);
FORCEPROP 0 LASTPIN (3575 2775) $PN 242
J 2
(3565 2785);
DISPLAY 0.680851 (3565 2785);
PAINT MONO (3565 2785);
FORCEPROP 0 LASTPIN (3575 2825) $PN 244
J 2
(3565 2835);
DISPLAY 0.680851 (3565 2835);
PAINT MONO (3565 2835);
FORCEPROP 0 LASTPIN (3575 2875) $PN 246
J 2
(3565 2885);
DISPLAY 0.680851 (3565 2885);
PAINT MONO (3565 2885);
FORCEPROP 0 LASTPIN (3575 2925) $PN 248
J 2
(3565 2935);
DISPLAY 0.680851 (3565 2935);
PAINT MONO (3565 2935);
FORCEPROP 0 LASTPIN (3575 2975) $PN 251
J 2
(3565 2985);
DISPLAY 0.680851 (3565 2985);
PAINT MONO (3565 2985);
FORCEPROP 0 LASTPIN (3575 3025) $PN 253
J 2
(3565 3035);
DISPLAY 0.680851 (3565 3035);
PAINT MONO (3565 3035);
FORCEPROP 0 LASTPIN (3575 3075) $PN 255
J 2
(3565 3085);
DISPLAY 0.680851 (3565 3085);
PAINT MONO (3565 3085);
FORCEPROP 0 LASTPIN (3575 3125) $PN 257
J 2
(3565 3135);
DISPLAY 0.680851 (3565 3135);
PAINT MONO (3565 3135);
FORCEPROP 0 LASTPIN (3575 3175) $PN 259
J 2
(3565 3185);
DISPLAY 0.680851 (3565 3185);
PAINT MONO (3565 3185);
FORCEPROP 0 LASTPIN (3575 3225) $PN 262
J 2
(3565 3235);
DISPLAY 0.680851 (3565 3235);
PAINT MONO (3565 3235);
FORCEPROP 0 LASTPIN (3575 3275) $PN 264
J 2
(3565 3285);
DISPLAY 0.680851 (3565 3285);
PAINT MONO (3565 3285);
FORCEPROP 0 LASTPIN (3575 3325) $PN 266
J 2
(3565 3335);
DISPLAY 0.680851 (3565 3335);
PAINT MONO (3565 3335);
FORCEPROP 0 LASTPIN (3575 3375) $PN 268
J 2
(3565 3385);
DISPLAY 0.680851 (3565 3385);
PAINT MONO (3565 3385);
FORCEPROP 0 LASTPIN (3575 3425) $PN 270
J 2
(3565 3435);
DISPLAY 0.680851 (3565 3435);
PAINT MONO (3565 3435);
FORCEPROP 0 LASTPIN (3575 3475) $PN 273
J 2
(3565 3485);
DISPLAY 0.680851 (3565 3485);
PAINT MONO (3565 3485);
FORCEPROP 0 LASTPIN (3575 3525) $PN 275
J 2
(3565 3535);
DISPLAY 0.680851 (3565 3535);
PAINT MONO (3565 3535);
FORCEPROP 0 LASTPIN (3575 3575) $PN 277
J 2
(3565 3585);
DISPLAY 0.680851 (3565 3585);
PAINT MONO (3565 3585);
FORCEPROP 0 LASTPIN (3575 3625) $PN 279
J 2
(3565 3635);
DISPLAY 0.680851 (3565 3635);
PAINT MONO (3565 3635);
FORCEPROP 0 LASTPIN (3575 3675) $PN 281
J 2
(3565 3685);
DISPLAY 0.680851 (3565 3685);
PAINT MONO (3565 3685);
FORCEPROP 0 LASTPIN (3575 3725) $PN 284
J 2
(3565 3735);
DISPLAY 0.680851 (3565 3735);
PAINT MONO (3565 3735);
FORCEPROP 0 LASTPIN (3575 3775) $PN 286
J 2
(3565 3785);
DISPLAY 0.680851 (3565 3785);
PAINT MONO (3565 3785);
FORCEPROP 0 LASTPIN (3575 3825) $PN 288
J 2
(3565 3835);
DISPLAY 0.680851 (3565 3835);
PAINT MONO (3565 3835);
FORCEPROP 1 LAST NEEDS_NO_SIZE TRUE
J 0
(4175 2350);
DISPLAY 0.723404 (4175 2350);
PAINT GREEN (4175 2350);
DISPLAY INVISIBLE (4175 2350);
FORCEPROP 1 LAST CDS_LMAN_SYM_OUTLINE -450,1775,450,-1775
J 0
(4175 2350);
DISPLAY 0.468085 (4175 2350);
PAINT GREEN (4175 2350);
DISPLAY INVISIBLE (4175 2350);
FORCEPROP 2 LAST CDS_LIB pure_quanta
J 0
(4175 2350);
DISPLAY INVISIBLE (4175 2350);
FORCEPROP 1 LAST PATH I178
J 0
(4175 2350);
DISPLAY 0.723404 (4175 2350);
PAINT GREEN (4175 2350);
DISPLAY INVISIBLE (4175 2350);
FORCEPROP 2 LAST CDS_LOCATION J25
J 0
(3725 4475);
DISPLAY 1.021277 (3725 4475);
DISPLAY INVISIBLE (3725 4475);
FORCEPROP 0 LAST $SEC 3
J 0
(3725 4475);
DISPLAY 0.680851 (3725 4475);
PAINT MONO (3725 4475);
DISPLAY INVISIBLE (3725 4475);
FORCEPROP 2 LAST CDS_SEC 3
J 0
(3725 4475);
DISPLAY 1.021277 (3725 4475);
DISPLAY INVISIBLE (3725 4475);
FORCEADD OFFPAGE..1
(-3675 2825);
FORCEPROP 2 LAST $XR0 55 
J 0
(-3896 2825);
DISPLAY 0.638298 (-3896 2825);
PAINT MONO (-3896 2825);
FORCEPROP 2 LAST CDS_LIB standard
J 0
(-3675 2825);
PAINT MONO (-3675 2825);
DISPLAY INVISIBLE (-3675 2825);
FORCEPROP 1 LAST OFFPAGE TRUE
J 0
(-3350 2700);
DISPLAY 0.872340 (-3350 2700);
DISPLAY INVISIBLE (-3350 2700);
FORCEPROP 1 LAST COMMENT_BODY TRUE
J 0
(-3550 2725);
DISPLAY 0.872340 (-3550 2725);
PAINT GREEN (-3550 2725);
DISPLAY INVISIBLE (-3550 2725);
FORCEPROP 2 LAST PATH I18
J 0
(-3625 2900);
DISPLAY 1.021277 (-3625 2900);
DISPLAY INVISIBLE (-3625 2900);
FORCEADD SCONN288_ADR50017P130CC..1
(-1925 2250);
FORCEPROP 1 LAST PART_NUMBER DFHST8FS461
J 0
(-2370 4272);
DISPLAY 0.723404 (-2370 4272);
PAINT GREEN (-2370 4272);
DISPLAY INVISIBLE (-2370 4272);
FORCEPROP 1 LAST MATERIAL IO
J 0
(-2370 4145);
DISPLAY 0.723404 (-2370 4145);
PAINT GREEN (-2370 4145);
FORCEPROP 2 LAST VALUE SCONN288_ADR50017-P130CC
J 0
(-2375 4375);
DISPLAY 1.021277 (-2375 4375);
FORCEPROP 2 LAST PART_TYPE SMLF
J 0
(-2375 4425);
DISPLAY 1.021277 (-2375 4425);
FORCEPROP 1 LAST $LOCATION J25
J 0
(-2375 4325);
DISPLAY 0.723404 (-2375 4325);
PAINT GREEN (-2375 4325);
FORCEPROP 0 LASTPIN (-2525 1625) $PN 62
J 2
(-2535 1635);
DISPLAY 0.680851 (-2535 1635);
PAINT MONO (-2535 1635);
FORCEPROP 0 LASTPIN (-2525 3675) $PN 66
J 2
(-2535 3685);
DISPLAY 0.680851 (-2535 3685);
PAINT MONO (-2535 3685);
FORCEPROP 0 LASTPIN (-2525 3275) $PN 76
J 2
(-2535 3285);
DISPLAY 0.680851 (-2535 3285);
PAINT MONO (-2535 3285);
FORCEPROP 0 LASTPIN (-2525 3725) $PN 211
J 2
(-2535 3735);
DISPLAY 0.680851 (-2535 3735);
PAINT MONO (-2535 3735);
FORCEPROP 0 LASTPIN (-2525 3325) $PN 221
J 2
(-2535 3335);
DISPLAY 0.680851 (-2535 3335);
PAINT MONO (-2535 3335);
FORCEPROP 0 LASTPIN (-2525 3775) $PN 68
J 2
(-2535 3785);
DISPLAY 0.680851 (-2535 3785);
PAINT MONO (-2535 3785);
FORCEPROP 0 LASTPIN (-2525 3375) $PN 78
J 2
(-2535 3385);
DISPLAY 0.680851 (-2535 3385);
PAINT MONO (-2535 3385);
FORCEPROP 0 LASTPIN (-2525 3825) $PN 213
J 2
(-2535 3835);
DISPLAY 0.680851 (-2535 3835);
PAINT MONO (-2535 3835);
FORCEPROP 0 LASTPIN (-2525 3425) $PN 223
J 2
(-2535 3435);
DISPLAY 0.680851 (-2535 3435);
PAINT MONO (-2535 3435);
FORCEPROP 0 LASTPIN (-2525 3875) $PN 70
J 2
(-2535 3885);
DISPLAY 0.680851 (-2535 3885);
PAINT MONO (-2535 3885);
FORCEPROP 0 LASTPIN (-2525 3475) $PN 80
J 2
(-2535 3485);
DISPLAY 0.680851 (-2535 3485);
PAINT MONO (-2535 3485);
FORCEPROP 0 LASTPIN (-2525 3925) $PN 215
J 2
(-2535 3935);
DISPLAY 0.680851 (-2535 3935);
PAINT MONO (-2535 3935);
FORCEPROP 0 LASTPIN (-2525 3525) $PN 225
J 2
(-2535 3535);
DISPLAY 0.680851 (-2535 3535);
PAINT MONO (-2535 3535);
FORCEPROP 0 LASTPIN (-2525 3975) $PN 72
J 2
(-2535 3985);
DISPLAY 0.680851 (-2535 3985);
PAINT MONO (-2535 3985);
FORCEPROP 0 LASTPIN (-2525 3575) $PN 82
J 2
(-2535 3585);
DISPLAY 0.680851 (-2535 3585);
PAINT MONO (-2535 3585);
FORCEPROP 0 LASTPIN (-2525 2225) $PN 51
J 2
(-2535 2235);
DISPLAY 0.680851 (-2535 2235);
PAINT MONO (-2535 2235);
FORCEPROP 0 LASTPIN (-2525 1775) $PN 96
J 2
(-2535 1785);
DISPLAY 0.680851 (-2535 1785);
PAINT MONO (-2535 1785);
FORCEPROP 0 LASTPIN (-2525 2275) $PN 53
J 2
(-2535 2285);
DISPLAY 0.680851 (-2535 2285);
PAINT MONO (-2535 2285);
FORCEPROP 0 LASTPIN (-2525 1825) $PN 98
J 2
(-2535 1835);
DISPLAY 0.680851 (-2535 1835);
PAINT MONO (-2535 1835);
FORCEPROP 0 LASTPIN (-2525 2325) $PN 196
J 2
(-2535 2335);
DISPLAY 0.680851 (-2535 2335);
PAINT MONO (-2535 2335);
FORCEPROP 0 LASTPIN (-2525 1875) $PN 241
J 2
(-2535 1885);
DISPLAY 0.680851 (-2535 1885);
PAINT MONO (-2535 1885);
FORCEPROP 0 LASTPIN (-2525 2375) $PN 198
J 2
(-2535 2385);
DISPLAY 0.680851 (-2535 2385);
PAINT MONO (-2535 2385);
FORCEPROP 0 LASTPIN (-2525 1925) $PN 243
J 2
(-2535 1935);
DISPLAY 0.680851 (-2535 1935);
PAINT MONO (-2535 1935);
FORCEPROP 0 LASTPIN (-2525 2425) $PN 58
J 2
(-2535 2435);
DISPLAY 0.680851 (-2535 2435);
PAINT MONO (-2535 2435);
FORCEPROP 0 LASTPIN (-2525 1975) $PN 89
J 2
(-2535 1985);
DISPLAY 0.680851 (-2535 1985);
PAINT MONO (-2535 1985);
FORCEPROP 0 LASTPIN (-2525 2475) $PN 60
J 2
(-2535 2485);
DISPLAY 0.680851 (-2535 2485);
PAINT MONO (-2535 2485);
FORCEPROP 0 LASTPIN (-2525 2025) $PN 91
J 2
(-2535 2035);
DISPLAY 0.680851 (-2535 2035);
PAINT MONO (-2535 2035);
FORCEPROP 0 LASTPIN (-2525 2525) $PN 203
J 2
(-2535 2535);
DISPLAY 0.680851 (-2535 2535);
PAINT MONO (-2535 2535);
FORCEPROP 0 LASTPIN (-2525 2075) $PN 234
J 2
(-2535 2085);
DISPLAY 0.680851 (-2535 2085);
PAINT MONO (-2535 2085);
FORCEPROP 0 LASTPIN (-2525 2575) $PN 205
J 2
(-2535 2585);
DISPLAY 0.680851 (-2535 2585);
PAINT MONO (-2535 2585);
FORCEPROP 0 LASTPIN (-2525 2125) $PN 236
J 2
(-2535 2135);
DISPLAY 0.680851 (-2535 2135);
PAINT MONO (-2535 2135);
FORCEPROP 0 LASTPIN (-2525 2675) $PN 218
J 2
(-2535 2685);
DISPLAY 0.680851 (-2535 2685);
PAINT MONO (-2535 2685);
FORCEPROP 0 LASTPIN (-2525 2725) $PN 217
J 2
(-2535 2735);
DISPLAY 0.680851 (-2535 2735);
PAINT MONO (-2535 2735);
FORCEPROP 0 LASTPIN (-2525 2975) $PN 64
J 2
(-2535 2985);
DISPLAY 0.680851 (-2535 2985);
PAINT MONO (-2535 2985);
FORCEPROP 0 LASTPIN (-2525 2825) $PN 84
J 2
(-2535 2835);
DISPLAY 0.680851 (-2535 2835);
PAINT MONO (-2535 2835);
FORCEPROP 0 LASTPIN (-2525 3025) $PN 209
J 2
(-2535 3035);
DISPLAY 0.680851 (-2535 3035);
PAINT MONO (-2535 3035);
FORCEPROP 0 LASTPIN (-2525 2875) $PN 229
J 2
(-2535 2885);
DISPLAY 0.680851 (-2535 2885);
PAINT MONO (-2535 2885);
FORCEPROP 0 LASTPIN (-1325 2425) $PN 7
J 0
(-1315 2435);
DISPLAY 0.680851 (-1315 2435);
PAINT MONO (-1315 2435);
FORCEPROP 0 LASTPIN (-1325 775) $PN 100
J 0
(-1315 785);
DISPLAY 0.680851 (-1315 785);
PAINT MONO (-1315 785);
FORCEPROP 0 LASTPIN (-1325 2475) $PN 9
J 0
(-1315 2485);
DISPLAY 0.680851 (-1315 2485);
PAINT MONO (-1315 2485);
FORCEPROP 0 LASTPIN (-1325 825) $PN 102
J 0
(-1315 835);
DISPLAY 0.680851 (-1315 835);
PAINT MONO (-1315 835);
FORCEPROP 0 LASTPIN (-1325 2525) $PN 152
J 0
(-1315 2535);
DISPLAY 0.680851 (-1315 2535);
PAINT MONO (-1315 2535);
FORCEPROP 0 LASTPIN (-1325 875) $PN 245
J 0
(-1315 885);
DISPLAY 0.680851 (-1315 885);
PAINT MONO (-1315 885);
FORCEPROP 0 LASTPIN (-1325 2575) $PN 154
J 0
(-1315 2585);
DISPLAY 0.680851 (-1315 2585);
PAINT MONO (-1315 2585);
FORCEPROP 0 LASTPIN (-1325 925) $PN 247
J 0
(-1315 935);
DISPLAY 0.680851 (-1315 935);
PAINT MONO (-1315 935);
FORCEPROP 0 LASTPIN (-1325 2625) $PN 14
J 0
(-1315 2635);
DISPLAY 0.680851 (-1315 2635);
PAINT MONO (-1315 2635);
FORCEPROP 0 LASTPIN (-1325 975) $PN 107
J 0
(-1315 985);
DISPLAY 0.680851 (-1315 985);
PAINT MONO (-1315 985);
FORCEPROP 0 LASTPIN (-1325 2675) $PN 16
J 0
(-1315 2685);
DISPLAY 0.680851 (-1315 2685);
PAINT MONO (-1315 2685);
FORCEPROP 0 LASTPIN (-1325 1025) $PN 109
J 0
(-1315 1035);
DISPLAY 0.680851 (-1315 1035);
PAINT MONO (-1315 1035);
FORCEPROP 0 LASTPIN (-1325 2725) $PN 159
J 0
(-1315 2735);
DISPLAY 0.680851 (-1315 2735);
PAINT MONO (-1315 2735);
FORCEPROP 0 LASTPIN (-1325 1075) $PN 252
J 0
(-1315 1085);
DISPLAY 0.680851 (-1315 1085);
PAINT MONO (-1315 1085);
FORCEPROP 0 LASTPIN (-1325 2775) $PN 161
J 0
(-1315 2785);
DISPLAY 0.680851 (-1315 2785);
PAINT MONO (-1315 2785);
FORCEPROP 0 LASTPIN (-1325 1125) $PN 254
J 0
(-1315 1135);
DISPLAY 0.680851 (-1315 1135);
PAINT MONO (-1315 1135);
FORCEPROP 0 LASTPIN (-1325 2825) $PN 18
J 0
(-1315 2835);
DISPLAY 0.680851 (-1315 2835);
PAINT MONO (-1315 2835);
FORCEPROP 0 LASTPIN (-1325 1175) $PN 111
J 0
(-1315 1185);
DISPLAY 0.680851 (-1315 1185);
PAINT MONO (-1315 1185);
FORCEPROP 0 LASTPIN (-1325 2875) $PN 20
J 0
(-1315 2885);
DISPLAY 0.680851 (-1315 2885);
PAINT MONO (-1315 2885);
FORCEPROP 0 LASTPIN (-1325 1225) $PN 113
J 0
(-1315 1235);
DISPLAY 0.680851 (-1315 1235);
PAINT MONO (-1315 1235);
FORCEPROP 0 LASTPIN (-1325 2925) $PN 163
J 0
(-1315 2935);
DISPLAY 0.680851 (-1315 2935);
PAINT MONO (-1315 2935);
FORCEPROP 0 LASTPIN (-1325 1275) $PN 256
J 0
(-1315 1285);
DISPLAY 0.680851 (-1315 1285);
PAINT MONO (-1315 1285);
FORCEPROP 0 LASTPIN (-1325 2975) $PN 165
J 0
(-1315 2985);
DISPLAY 0.680851 (-1315 2985);
PAINT MONO (-1315 2985);
FORCEPROP 0 LASTPIN (-1325 1325) $PN 258
J 0
(-1315 1335);
DISPLAY 0.680851 (-1315 1335);
PAINT MONO (-1315 1335);
FORCEPROP 0 LASTPIN (-1325 3025) $PN 25
J 0
(-1315 3035);
DISPLAY 0.680851 (-1315 3035);
PAINT MONO (-1315 3035);
FORCEPROP 0 LASTPIN (-1325 1375) $PN 118
J 0
(-1315 1385);
DISPLAY 0.680851 (-1315 1385);
PAINT MONO (-1315 1385);
FORCEPROP 0 LASTPIN (-1325 3075) $PN 27
J 0
(-1315 3085);
DISPLAY 0.680851 (-1315 3085);
PAINT MONO (-1315 3085);
FORCEPROP 0 LASTPIN (-1325 1425) $PN 120
J 0
(-1315 1435);
DISPLAY 0.680851 (-1315 1435);
PAINT MONO (-1315 1435);
FORCEPROP 0 LASTPIN (-1325 3125) $PN 170
J 0
(-1315 3135);
DISPLAY 0.680851 (-1315 3135);
PAINT MONO (-1315 3135);
FORCEPROP 0 LASTPIN (-1325 1475) $PN 263
J 0
(-1315 1485);
DISPLAY 0.680851 (-1315 1485);
PAINT MONO (-1315 1485);
FORCEPROP 0 LASTPIN (-1325 3175) $PN 172
J 0
(-1315 3185);
DISPLAY 0.680851 (-1315 3185);
PAINT MONO (-1315 3185);
FORCEPROP 0 LASTPIN (-1325 1525) $PN 265
J 0
(-1315 1535);
DISPLAY 0.680851 (-1315 1535);
PAINT MONO (-1315 1535);
FORCEPROP 0 LASTPIN (-1325 3225) $PN 29
J 0
(-1315 3235);
DISPLAY 0.680851 (-1315 3235);
PAINT MONO (-1315 3235);
FORCEPROP 0 LASTPIN (-1325 1575) $PN 122
J 0
(-1315 1585);
DISPLAY 0.680851 (-1315 1585);
PAINT MONO (-1315 1585);
FORCEPROP 0 LASTPIN (-1325 3275) $PN 31
J 0
(-1315 3285);
DISPLAY 0.680851 (-1315 3285);
PAINT MONO (-1315 3285);
FORCEPROP 0 LASTPIN (-1325 1625) $PN 124
J 0
(-1315 1635);
DISPLAY 0.680851 (-1315 1635);
PAINT MONO (-1315 1635);
FORCEPROP 0 LASTPIN (-1325 3325) $PN 174
J 0
(-1315 3335);
DISPLAY 0.680851 (-1315 3335);
PAINT MONO (-1315 3335);
FORCEPROP 0 LASTPIN (-1325 1675) $PN 267
J 0
(-1315 1685);
DISPLAY 0.680851 (-1315 1685);
PAINT MONO (-1315 1685);
FORCEPROP 0 LASTPIN (-1325 3375) $PN 176
J 0
(-1315 3385);
DISPLAY 0.680851 (-1315 3385);
PAINT MONO (-1315 3385);
FORCEPROP 0 LASTPIN (-1325 1725) $PN 269
J 0
(-1315 1735);
DISPLAY 0.680851 (-1315 1735);
PAINT MONO (-1315 1735);
FORCEPROP 0 LASTPIN (-1325 3425) $PN 36
J 0
(-1315 3435);
DISPLAY 0.680851 (-1315 3435);
PAINT MONO (-1315 3435);
FORCEPROP 0 LASTPIN (-1325 1775) $PN 129
J 0
(-1315 1785);
DISPLAY 0.680851 (-1315 1785);
PAINT MONO (-1315 1785);
FORCEPROP 0 LASTPIN (-1325 3475) $PN 38
J 0
(-1315 3485);
DISPLAY 0.680851 (-1315 3485);
PAINT MONO (-1315 3485);
FORCEPROP 0 LASTPIN (-1325 1825) $PN 131
J 0
(-1315 1835);
DISPLAY 0.680851 (-1315 1835);
PAINT MONO (-1315 1835);
FORCEPROP 0 LASTPIN (-1325 3525) $PN 181
J 0
(-1315 3535);
DISPLAY 0.680851 (-1315 3535);
PAINT MONO (-1315 3535);
FORCEPROP 0 LASTPIN (-1325 1875) $PN 274
J 0
(-1315 1885);
DISPLAY 0.680851 (-1315 1885);
PAINT MONO (-1315 1885);
FORCEPROP 0 LASTPIN (-1325 3575) $PN 183
J 0
(-1315 3585);
DISPLAY 0.680851 (-1315 3585);
PAINT MONO (-1315 3585);
FORCEPROP 0 LASTPIN (-1325 1925) $PN 276
J 0
(-1315 1935);
DISPLAY 0.680851 (-1315 1935);
PAINT MONO (-1315 1935);
FORCEPROP 0 LASTPIN (-1325 3625) $PN 40
J 0
(-1315 3635);
DISPLAY 0.680851 (-1315 3635);
PAINT MONO (-1315 3635);
FORCEPROP 0 LASTPIN (-1325 1975) $PN 133
J 0
(-1315 1985);
DISPLAY 0.680851 (-1315 1985);
PAINT MONO (-1315 1985);
FORCEPROP 0 LASTPIN (-1325 3675) $PN 42
J 0
(-1315 3685);
DISPLAY 0.680851 (-1315 3685);
PAINT MONO (-1315 3685);
FORCEPROP 0 LASTPIN (-1325 2025) $PN 135
J 0
(-1315 2035);
DISPLAY 0.680851 (-1315 2035);
PAINT MONO (-1315 2035);
FORCEPROP 0 LASTPIN (-1325 3725) $PN 185
J 0
(-1315 3735);
DISPLAY 0.680851 (-1315 3735);
PAINT MONO (-1315 3735);
FORCEPROP 0 LASTPIN (-1325 2075) $PN 278
J 0
(-1315 2085);
DISPLAY 0.680851 (-1315 2085);
PAINT MONO (-1315 2085);
FORCEPROP 0 LASTPIN (-1325 3775) $PN 187
J 0
(-1315 3785);
DISPLAY 0.680851 (-1315 3785);
PAINT MONO (-1315 3785);
FORCEPROP 0 LASTPIN (-1325 2125) $PN 280
J 0
(-1315 2135);
DISPLAY 0.680851 (-1315 2135);
PAINT MONO (-1315 2135);
FORCEPROP 0 LASTPIN (-1325 3825) $PN 47
J 0
(-1315 3835);
DISPLAY 0.680851 (-1315 3835);
PAINT MONO (-1315 3835);
FORCEPROP 0 LASTPIN (-1325 2175) $PN 140
J 0
(-1315 2185);
DISPLAY 0.680851 (-1315 2185);
PAINT MONO (-1315 2185);
FORCEPROP 0 LASTPIN (-1325 3875) $PN 49
J 0
(-1315 3885);
DISPLAY 0.680851 (-1315 3885);
PAINT MONO (-1315 3885);
FORCEPROP 0 LASTPIN (-1325 2225) $PN 142
J 0
(-1315 2235);
DISPLAY 0.680851 (-1315 2235);
PAINT MONO (-1315 2235);
FORCEPROP 0 LASTPIN (-1325 3925) $PN 192
J 0
(-1315 3935);
DISPLAY 0.680851 (-1315 3935);
PAINT MONO (-1315 3935);
FORCEPROP 0 LASTPIN (-1325 2275) $PN 285
J 0
(-1315 2285);
DISPLAY 0.680851 (-1315 2285);
PAINT MONO (-1315 2285);
FORCEPROP 0 LASTPIN (-1325 3975) $PN 194
J 0
(-1315 3985);
DISPLAY 0.680851 (-1315 3985);
PAINT MONO (-1315 3985);
FORCEPROP 0 LASTPIN (-1325 2325) $PN 287
J 0
(-1315 2335);
DISPLAY 0.680851 (-1315 2335);
PAINT MONO (-1315 2335);
FORCEPROP 0 LASTPIN (-2525 1475) $PN 148
J 2
(-2535 1485);
DISPLAY 0.680851 (-2535 1485);
PAINT MONO (-2535 1485);
FORCEPROP 0 LASTPIN (-2525 1375) $PN 4
J 2
(-2535 1385);
DISPLAY 0.680851 (-2535 1385);
PAINT MONO (-2535 1385);
FORCEPROP 0 LASTPIN (-2525 1425) $PN 5
J 2
(-2535 1435);
DISPLAY 0.680851 (-2535 1435);
PAINT MONO (-2535 1435);
FORCEPROP 0 LASTPIN (-2525 575) $PN 86
J 2
(-2535 585);
DISPLAY 0.680851 (-2535 585);
PAINT MONO (-2535 585);
FORCEPROP 0 LASTPIN (-2525 525) $PN 87
J 2
(-2535 535);
DISPLAY 0.680851 (-2535 535);
PAINT MONO (-2535 535);
FORCEPROP 0 LASTPIN (-2525 3175) $PN 74
J 2
(-2535 3185);
DISPLAY 0.680851 (-2535 3185);
PAINT MONO (-2535 3185);
FORCEPROP 0 LASTPIN (-2525 3125) $PN 227
J 2
(-2535 3135);
DISPLAY 0.680851 (-2535 3135);
PAINT MONO (-2535 3135);
FORCEPROP 0 LASTPIN (-2525 1125) $PN 147
J 2
(-2535 1135);
DISPLAY 0.680851 (-2535 1135);
PAINT MONO (-2535 1135);
FORCEPROP 0 LASTPIN (-2525 1675) $PN 207
J 2
(-2535 1685);
DISPLAY 0.680851 (-2535 1685);
PAINT MONO (-2535 1685);
FORCEPROP 0 LASTPIN (-2525 725) $PN 2
J 2
(-2535 735);
DISPLAY 0.680851 (-2535 735);
PAINT MONO (-2535 735);
FORCEPROP 0 LASTPIN (-2525 775) $PN 144
J 2
(-2535 785);
DISPLAY 0.680851 (-2535 785);
PAINT MONO (-2535 785);
FORCEPROP 0 LASTPIN (-2525 825) $PN 149
J 2
(-2535 835);
DISPLAY 0.680851 (-2535 835);
PAINT MONO (-2535 835);
FORCEPROP 0 LASTPIN (-2525 875) $PN 150
J 2
(-2535 885);
DISPLAY 0.680851 (-2535 885);
PAINT MONO (-2535 885);
FORCEPROP 0 LASTPIN (-2525 925) $PN 220
J 2
(-2535 935);
DISPLAY 0.680851 (-2535 935);
PAINT MONO (-2535 935);
FORCEPROP 0 LASTPIN (-2525 975) $PN 231
J 2
(-2535 985);
DISPLAY 0.680851 (-2535 985);
PAINT MONO (-2535 985);
FORCEPROP 0 LASTPIN (-2525 1025) $PN 232
J 2
(-2535 1035);
DISPLAY 0.680851 (-2535 1035);
PAINT MONO (-2535 1035);
FORCEPROP 0 LASTPIN (-2525 1525) $PN 3
J 2
(-2535 1535);
DISPLAY 0.680851 (-2535 1535);
PAINT MONO (-2535 1535);
FORCEPROP 1 LAST NEEDS_NO_SIZE TRUE
J 0
(-1925 2250);
DISPLAY 0.723404 (-1925 2250);
PAINT GREEN (-1925 2250);
DISPLAY INVISIBLE (-1925 2250);
FORCEPROP 1 LAST CDS_LMAN_SYM_OUTLINE -450,1875,450,-1875
J 0
(-1925 2250);
DISPLAY 0.468085 (-1925 2250);
PAINT GREEN (-1925 2250);
DISPLAY INVISIBLE (-1925 2250);
FORCEPROP 2 LAST CDS_LIB pure_quanta
J 0
(-1925 2250);
DISPLAY INVISIBLE (-1925 2250);
FORCEPROP 1 LAST PATH I180
J 0
(-1925 2250);
DISPLAY 0.723404 (-1925 2250);
PAINT GREEN (-1925 2250);
DISPLAY INVISIBLE (-1925 2250);
FORCEPROP 2 LAST CDS_LOCATION J25
J 0
(-2375 4475);
DISPLAY 1.021277 (-2375 4475);
DISPLAY INVISIBLE (-2375 4475);
FORCEPROP 0 LAST $SEC 1
J 0
(-2350 4475);
DISPLAY 0.680851 (-2350 4475);
PAINT MONO (-2350 4475);
DISPLAY INVISIBLE (-2350 4475);
FORCEPROP 2 LAST CDS_SEC 1
J 0
(-2375 4475);
DISPLAY 1.021277 (-2375 4475);
DISPLAY INVISIBLE (-2375 4475);
FORCEADD SCONN288_ADR50017P130CC..2
(750 2975);
FORCEPROP 1 LAST PART_NUMBER DFHST8FS461
J 0
(157 4275);
DISPLAY 0.723404 (157 4275);
PAINT GREEN (157 4275);
DISPLAY INVISIBLE (157 4275);
FORCEPROP 1 LAST MATERIAL IO
J 0
(157 4148);
DISPLAY 0.723404 (157 4148);
PAINT GREEN (157 4148);
FORCEPROP 2 LAST PART_TYPE SMLF
J 0
(168 4428);
DISPLAY 1.021277 (168 4428);
FORCEPROP 2 LAST VALUE SCONN288_ADR50017-P130CC
J 0
(168 4378);
DISPLAY 1.021277 (168 4378);
FORCEPROP 1 LAST LOCATION J25
J 0
(150 4325);
DISPLAY 0.723404 (150 4325);
PAINT GREEN (150 4325);
FORCEPROP 0 LASTPIN (1500 3025) $PN 12
J 0
(1510 3035);
DISPLAY 0.680851 (1510 3035);
PAINT MONO (1510 3035);
FORCEPROP 0 LASTPIN (1500 3075) $PN 11
J 0
(1510 3085);
DISPLAY 0.680851 (1510 3085);
PAINT MONO (1510 3085);
FORCEPROP 0 LASTPIN (1500 1975) $PN 105
J 0
(1510 1985);
DISPLAY 0.680851 (1510 1985);
PAINT MONO (1510 1985);
FORCEPROP 0 LASTPIN (1500 2025) $PN 104
J 0
(1510 2035);
DISPLAY 0.680851 (1510 2035);
PAINT MONO (1510 2035);
FORCEPROP 0 LASTPIN (1500 3125) $PN 23
J 0
(1510 3135);
DISPLAY 0.680851 (1510 3135);
PAINT MONO (1510 3135);
FORCEPROP 0 LASTPIN (1500 3175) $PN 22
J 0
(1510 3185);
DISPLAY 0.680851 (1510 3185);
PAINT MONO (1510 3185);
FORCEPROP 0 LASTPIN (1500 2075) $PN 116
J 0
(1510 2085);
DISPLAY 0.680851 (1510 2085);
PAINT MONO (1510 2085);
FORCEPROP 0 LASTPIN (1500 2125) $PN 115
J 0
(1510 2135);
DISPLAY 0.680851 (1510 2135);
PAINT MONO (1510 2135);
FORCEPROP 0 LASTPIN (1500 3225) $PN 34
J 0
(1510 3235);
DISPLAY 0.680851 (1510 3235);
PAINT MONO (1510 3235);
FORCEPROP 0 LASTPIN (1500 3275) $PN 33
J 0
(1510 3285);
DISPLAY 0.680851 (1510 3285);
PAINT MONO (1510 3285);
FORCEPROP 0 LASTPIN (1500 2175) $PN 127
J 0
(1510 2185);
DISPLAY 0.680851 (1510 2185);
PAINT MONO (1510 2185);
FORCEPROP 0 LASTPIN (1500 2225) $PN 126
J 0
(1510 2235);
DISPLAY 0.680851 (1510 2235);
PAINT MONO (1510 2235);
FORCEPROP 0 LASTPIN (1500 3325) $PN 45
J 0
(1510 3335);
DISPLAY 0.680851 (1510 3335);
PAINT MONO (1510 3335);
FORCEPROP 0 LASTPIN (1500 3375) $PN 44
J 0
(1510 3385);
DISPLAY 0.680851 (1510 3385);
PAINT MONO (1510 3385);
FORCEPROP 0 LASTPIN (1500 2275) $PN 138
J 0
(1510 2285);
DISPLAY 0.680851 (1510 2285);
PAINT MONO (1510 2285);
FORCEPROP 0 LASTPIN (1500 2325) $PN 137
J 0
(1510 2335);
DISPLAY 0.680851 (1510 2335);
PAINT MONO (1510 2335);
FORCEPROP 0 LASTPIN (1500 3425) $PN 56
J 0
(1510 3435);
DISPLAY 0.680851 (1510 3435);
PAINT MONO (1510 3435);
FORCEPROP 0 LASTPIN (1500 3475) $PN 55
J 0
(1510 3485);
DISPLAY 0.680851 (1510 3485);
PAINT MONO (1510 3485);
FORCEPROP 0 LASTPIN (1500 2375) $PN 238
J 0
(1510 2385);
DISPLAY 0.680851 (1510 2385);
PAINT MONO (1510 2385);
FORCEPROP 0 LASTPIN (1500 2425) $PN 239
J 0
(1510 2435);
DISPLAY 0.680851 (1510 2435);
PAINT MONO (1510 2435);
FORCEPROP 0 LASTPIN (1500 3525) $PN 156
J 0
(1510 3535);
DISPLAY 0.680851 (1510 3535);
PAINT MONO (1510 3535);
FORCEPROP 0 LASTPIN (1500 3575) $PN 157
J 0
(1510 3585);
DISPLAY 0.680851 (1510 3585);
PAINT MONO (1510 3585);
FORCEPROP 0 LASTPIN (1500 2475) $PN 249
J 0
(1510 2485);
DISPLAY 0.680851 (1510 2485);
PAINT MONO (1510 2485);
FORCEPROP 0 LASTPIN (1500 2525) $PN 250
J 0
(1510 2535);
DISPLAY 0.680851 (1510 2535);
PAINT MONO (1510 2535);
FORCEPROP 0 LASTPIN (1500 3625) $PN 167
J 0
(1510 3635);
DISPLAY 0.680851 (1510 3635);
PAINT MONO (1510 3635);
FORCEPROP 0 LASTPIN (1500 3675) $PN 168
J 0
(1510 3685);
DISPLAY 0.680851 (1510 3685);
PAINT MONO (1510 3685);
FORCEPROP 0 LASTPIN (1500 2575) $PN 260
J 0
(1510 2585);
DISPLAY 0.680851 (1510 2585);
PAINT MONO (1510 2585);
FORCEPROP 0 LASTPIN (1500 2625) $PN 261
J 0
(1510 2635);
DISPLAY 0.680851 (1510 2635);
PAINT MONO (1510 2635);
FORCEPROP 0 LASTPIN (1500 3725) $PN 178
J 0
(1510 3735);
DISPLAY 0.680851 (1510 3735);
PAINT MONO (1510 3735);
FORCEPROP 0 LASTPIN (1500 3775) $PN 179
J 0
(1510 3785);
DISPLAY 0.680851 (1510 3785);
PAINT MONO (1510 3785);
FORCEPROP 0 LASTPIN (1500 2675) $PN 271
J 0
(1510 2685);
DISPLAY 0.680851 (1510 2685);
PAINT MONO (1510 2685);
FORCEPROP 0 LASTPIN (1500 2725) $PN 272
J 0
(1510 2735);
DISPLAY 0.680851 (1510 2735);
PAINT MONO (1510 2735);
FORCEPROP 0 LASTPIN (1500 3825) $PN 189
J 0
(1510 3835);
DISPLAY 0.680851 (1510 3835);
PAINT MONO (1510 3835);
FORCEPROP 0 LASTPIN (1500 3875) $PN 190
J 0
(1510 3885);
DISPLAY 0.680851 (1510 3885);
PAINT MONO (1510 3885);
FORCEPROP 0 LASTPIN (1500 2775) $PN 282
J 0
(1510 2785);
DISPLAY 0.680851 (1510 2785);
PAINT MONO (1510 2785);
FORCEPROP 0 LASTPIN (1500 2825) $PN 283
J 0
(1510 2835);
DISPLAY 0.680851 (1510 2835);
PAINT MONO (1510 2835);
FORCEPROP 0 LASTPIN (1500 3925) $PN 200
J 0
(1510 3935);
DISPLAY 0.680851 (1510 3935);
PAINT MONO (1510 3935);
FORCEPROP 0 LASTPIN (1500 3975) $PN 201
J 0
(1510 3985);
DISPLAY 0.680851 (1510 3985);
PAINT MONO (1510 3985);
FORCEPROP 0 LASTPIN (1500 2875) $PN 94
J 0
(1510 2885);
DISPLAY 0.680851 (1510 2885);
PAINT MONO (1510 2885);
FORCEPROP 0 LASTPIN (1500 2925) $PN 93
J 0
(1510 2935);
DISPLAY 0.680851 (1510 2935);
PAINT MONO (1510 2935);
FORCEPROP 1 LAST NEEDS_NO_SIZE TRUE
J 0
(750 2975);
DISPLAY 0.723404 (750 2975);
PAINT GREEN (750 2975);
DISPLAY INVISIBLE (750 2975);
FORCEPROP 1 LAST CDS_LMAN_SYM_OUTLINE -600,1150,600,-1150
J 0
(750 2975);
DISPLAY 0.468085 (750 2975);
PAINT GREEN (750 2975);
DISPLAY INVISIBLE (750 2975);
FORCEPROP 2 LAST CDS_LIB pure_quanta
J 0
(750 2975);
DISPLAY INVISIBLE (750 2975);
FORCEPROP 1 LAST PATH I181
J 0
(750 2975);
DISPLAY 0.723404 (750 2975);
PAINT GREEN (750 2975);
DISPLAY INVISIBLE (750 2975);
FORCEPROP 0 LAST $SEC 2
J 0
(175 4500);
DISPLAY 0.680851 (175 4500);
PAINT MONO (175 4500);
DISPLAY INVISIBLE (175 4500);
FORCEPROP 0 LAST CDS_SEC 2
J 0
(175 4500);
DISPLAY 1.021277 (175 4500);
DISPLAY INVISIBLE (175 4500);
FORCEADD OFFPAGE..1
(-2525 1225);
FORCEPROP 2 LAST $XR7 113 
J 0
(-3617 1225);
DISPLAY 0.638298 (-3617 1225);
PAINT MONO (-3617 1225);
FORCEPROP 2 LAST $XR6 112 
J 0
(-3497 1225);
DISPLAY 0.638298 (-3497 1225);
PAINT MONO (-3497 1225);
FORCEPROP 2 LAST $XR5 111 
J 0
(-3377 1225);
DISPLAY 0.638298 (-3377 1225);
PAINT MONO (-3377 1225);
FORCEPROP 2 LAST $XR4 110 
J 0
(-3257 1225);
DISPLAY 0.638298 (-3257 1225);
PAINT MONO (-3257 1225);
FORCEPROP 2 LAST $XR3 109 
J 0
(-3137 1225);
DISPLAY 0.638298 (-3137 1225);
PAINT MONO (-3137 1225);
FORCEPROP 2 LAST $XR2 108 
J 0
(-3017 1225);
DISPLAY 0.638298 (-3017 1225);
PAINT MONO (-3017 1225);
FORCEPROP 2 LAST $XR1 107 
J 0
(-2897 1225);
DISPLAY 0.638298 (-2897 1225);
PAINT MONO (-2897 1225);
FORCEPROP 2 LAST $XR0 230 
J 0
(-2777 1225);
DISPLAY 0.638298 (-2777 1225);
PAINT MONO (-2777 1225);
FORCEPROP 2 LAST CDS_LIB standard
J 2
(-2525 1225);
DISPLAY INVISIBLE (-2525 1225);
FORCEPROP 1 LAST OFFPAGE TRUE
J 0
(-2200 1100);
DISPLAY 0.872340 (-2200 1100);
DISPLAY INVISIBLE (-2200 1100);
FORCEPROP 1 LAST COMMENT_BODY TRUE
J 0
(-2400 1125);
DISPLAY 0.872340 (-2400 1125);
PAINT GREEN (-2400 1125);
DISPLAY INVISIBLE (-2400 1125);
FORCEPROP 2 LAST PATH I182
J 2
(-2700 1300);
DISPLAY 1.021277 (-2700 1300);
DISPLAY INVISIBLE (-2700 1300);
FORCEADD Q_RES..1
(-3725 1275);
FORCEPROP 1 LAST PART_NUMBER CS04992FB07
J 0
(-3625 1250);
DISPLAY 0.404255 (-3625 1250);
DISPLAY INVISIBLE (-3625 1250);
FORCEPROP 1 LAST VALUE 49.9
J 2
(-3500 1275);
DISPLAY 0.510638 (-3500 1275);
FORCEPROP 1 LAST MATERIAL CHIP
J 0
(-3875 1250);
DISPLAY 0.404255 (-3875 1250);
FORCEPROP 1 LAST $LOCATION R3899
J 0
(-3975 1275);
DISPLAY 0.638298 (-3975 1275);
FORCEPROP 1 LASTPIN (-3825 1275) $PN 1
J 0
(-3813 1287);
DISPLAY 0.787234 (-3813 1287);
PAINT MONO (-3813 1287);
FORCEPROP 1 LASTPIN (-3625 1275) $PN 2
J 0
(-3663 1287);
DISPLAY 0.787234 (-3663 1287);
PAINT MONO (-3663 1287);
FORCEPROP 2 LAST CDS_LIB pure_quanta
J 0
(-3725 1275);
DISPLAY INVISIBLE (-3725 1275);
FORCEPROP 1 LAST PACK_TYPE 0402LF
J 0
(-3425 1275);
DISPLAY 0.510638 (-3425 1275);
DISPLAY INVISIBLE (-3425 1275);
FORCEPROP 1 LAST TOLERANCE 1%
J 0
(-3500 1275);
DISPLAY 0.510638 (-3500 1275);
DISPLAY INVISIBLE (-3500 1275);
FORCEPROP 1 LAST WATTAGE 1/16W
J 2
(-3425 1225);
DISPLAY 0.404255 (-3425 1225);
DISPLAY INVISIBLE (-3425 1225);
FORCEPROP 1 LAST PATH I183
J 0
(-3775 1425);
DISPLAY 0.978723 (-3775 1425);
PAINT WHITE (-3775 1425);
DISPLAY INVISIBLE (-3775 1425);
FORCEPROP 0 LAST CDS_LOCATION R3899
J 0
(-3875 1325);
DISPLAY 1.021277 (-3875 1325);
DISPLAY INVISIBLE (-3875 1325);
FORCEPROP 0 LAST $SEC 1
J 0
(-3875 1325);
DISPLAY 0.680851 (-3875 1325);
PAINT MONO (-3875 1325);
DISPLAY INVISIBLE (-3875 1325);
FORCEPROP 0 LAST CDS_SEC 1
J 0
(-3875 1325);
DISPLAY 1.021277 (-3875 1325);
DISPLAY INVISIBLE (-3875 1325);
FORCEADD OFFPAGE..1
(-3675 2975);
FORCEPROP 2 LAST $XR0 55 
J 0
(-3896 2975);
DISPLAY 0.638298 (-3896 2975);
PAINT MONO (-3896 2975);
FORCEPROP 2 LAST CDS_LIB standard
J 0
(-3675 2975);
PAINT MONO (-3675 2975);
DISPLAY INVISIBLE (-3675 2975);
FORCEPROP 1 LAST OFFPAGE TRUE
J 0
(-3350 2850);
DISPLAY 0.872340 (-3350 2850);
DISPLAY INVISIBLE (-3350 2850);
FORCEPROP 1 LAST COMMENT_BODY TRUE
J 0
(-3550 2875);
DISPLAY 0.872340 (-3550 2875);
PAINT GREEN (-3550 2875);
DISPLAY INVISIBLE (-3550 2875);
FORCEPROP 2 LAST PATH I19
J 0
(-3625 3050);
DISPLAY 1.021277 (-3625 3050);
DISPLAY INVISIBLE (-3625 3050);
FORCEADD Q_RES..2
(-2525 -175);
FORCEPROP 1 LAST PART_NUMBER CS31002FB08
J 0
(-2485 -300);
DISPLAY 0.978723 (-2485 -300);
DISPLAY INVISIBLE (-2485 -300);
FORCEPROP 1 LAST VALUE 10K
J 0
(-2480 -100);
DISPLAY 0.978723 (-2480 -100);
FORCEPROP 1 LAST TOLERANCE 1%
J 0
(-2480 -150);
DISPLAY 0.978723 (-2480 -150);
FORCEPROP 1 LAST WATTAGE 1/16W
J 0
(-2485 -200);
DISPLAY 0.978723 (-2485 -200);
FORCEPROP 1 LAST MATERIAL CHIP
J 0
(-2485 -250);
DISPLAY 0.978723 (-2485 -250);
FORCEPROP 1 LAST PACK_TYPE 0402LF
J 0
(-2485 -350);
DISPLAY 0.978723 (-2485 -350);
FORCEPROP 1 LAST $LOCATION R79
J 0
(-2480 -50);
DISPLAY 0.978723 (-2480 -50);
FORCEPROP 1 LASTPIN (-2525 -75) $PN 1
J 0
(-2520 -113);
DISPLAY 0.787234 (-2520 -113);
FORCEPROP 1 LASTPIN (-2525 -275) $PN 2
J 0
(-2520 -265);
DISPLAY 0.787234 (-2520 -265);
FORCEPROP 2 LAST CDS_LIB pure_quanta
J 0
(-2525 -175);
PAINT MONO (-2525 -175);
DISPLAY INVISIBLE (-2525 -175);
FORCEPROP 1 LAST PATH I2
J 0
(-2475 0);
DISPLAY 0.978723 (-2475 0);
PAINT WHITE (-2475 0);
DISPLAY INVISIBLE (-2475 0);
FORCEPROP 1 LAST $LOCATION R79
J 0
(-2475 50);
DISPLAY 1.021277 (-2475 50);
DISPLAY INVISIBLE (-2475 50);
FORCEPROP 2 LAST CDS_LOCATION R79
J 0
(-2475 50);
DISPLAY 1.021277 (-2475 50);
DISPLAY INVISIBLE (-2475 50);
FORCEPROP 2 LAST $SEC 1
J 0
(-2475 50);
DISPLAY 0.680851 (-2475 50);
PAINT MONO (-2475 50);
DISPLAY INVISIBLE (-2475 50);
FORCEPROP 2 LAST CDS_SEC 1
J 0
(-2475 50);
DISPLAY 1.021277 (-2475 50);
DISPLAY INVISIBLE (-2475 50);
FORCEADD OFFPAGE..1
(-3675 3025);
FORCEPROP 2 LAST $XR0 55 
J 0
(-3896 3025);
DISPLAY 0.638298 (-3896 3025);
PAINT MONO (-3896 3025);
FORCEPROP 2 LAST CDS_LIB standard
J 0
(-3675 3025);
PAINT MONO (-3675 3025);
DISPLAY INVISIBLE (-3675 3025);
FORCEPROP 1 LAST OFFPAGE TRUE
J 0
(-3350 2900);
DISPLAY 0.872340 (-3350 2900);
DISPLAY INVISIBLE (-3350 2900);
FORCEPROP 1 LAST COMMENT_BODY TRUE
J 0
(-3550 2925);
DISPLAY 0.872340 (-3550 2925);
PAINT GREEN (-3550 2925);
DISPLAY INVISIBLE (-3550 2925);
FORCEPROP 2 LAST PATH I20
J 0
(-3625 3100);
DISPLAY 1.021277 (-3625 3100);
DISPLAY INVISIBLE (-3625 3100);
FORCEADD OFFPAGE..1
(-3675 3175);
FORCEPROP 2 LAST $XR1 107 
J 0
(-4016 3175);
DISPLAY 0.638298 (-4016 3175);
PAINT MONO (-4016 3175);
FORCEPROP 2 LAST $XR0 55 
J 0
(-3896 3175);
DISPLAY 0.638298 (-3896 3175);
PAINT MONO (-3896 3175);
FORCEPROP 2 LAST CDS_LIB standard
J 0
(-3675 3175);
PAINT MONO (-3675 3175);
DISPLAY INVISIBLE (-3675 3175);
FORCEPROP 1 LAST OFFPAGE TRUE
J 0
(-3350 3050);
DISPLAY 0.872340 (-3350 3050);
DISPLAY INVISIBLE (-3350 3050);
FORCEPROP 1 LAST COMMENT_BODY TRUE
J 0
(-3550 3075);
DISPLAY 0.872340 (-3550 3075);
PAINT GREEN (-3550 3075);
DISPLAY INVISIBLE (-3550 3075);
FORCEPROP 2 LAST PATH I21
J 0
(-3625 3250);
DISPLAY 1.021277 (-3625 3250);
DISPLAY INVISIBLE (-3625 3250);
FORCEADD OFFPAGE..1
(-3675 3125);
FORCEPROP 2 LAST $XR1 107 
J 0
(-4016 3125);
DISPLAY 0.638298 (-4016 3125);
PAINT MONO (-4016 3125);
FORCEPROP 2 LAST $XR0 55 
J 0
(-3896 3125);
DISPLAY 0.638298 (-3896 3125);
PAINT MONO (-3896 3125);
FORCEPROP 2 LAST CDS_LIB standard
J 0
(-3675 3125);
PAINT MONO (-3675 3125);
DISPLAY INVISIBLE (-3675 3125);
FORCEPROP 1 LAST OFFPAGE TRUE
J 0
(-3350 3000);
DISPLAY 0.872340 (-3350 3000);
DISPLAY INVISIBLE (-3350 3000);
FORCEPROP 1 LAST COMMENT_BODY TRUE
J 0
(-3550 3025);
DISPLAY 0.872340 (-3550 3025);
PAINT GREEN (-3550 3025);
DISPLAY INVISIBLE (-3550 3025);
FORCEPROP 2 LAST PATH I22
J 0
(-3625 3200);
DISPLAY 1.021277 (-3625 3200);
DISPLAY INVISIBLE (-3625 3200);
FORCEADD OFFPAGE..1
(-3675 3600);
FORCEPROP 2 LAST $XR1 107 
J 0
(-4016 3600);
DISPLAY 0.638298 (-4016 3600);
PAINT MONO (-4016 3600);
FORCEPROP 2 LAST $XR0 55 
J 0
(-3896 3600);
DISPLAY 0.638298 (-3896 3600);
PAINT MONO (-3896 3600);
FORCEPROP 2 LAST CDS_LIB standard
J 0
(-3675 3600);
PAINT MONO (-3675 3600);
DISPLAY INVISIBLE (-3675 3600);
FORCEPROP 1 LAST OFFPAGE TRUE
J 0
(-3350 3475);
DISPLAY 0.872340 (-3350 3475);
DISPLAY INVISIBLE (-3350 3475);
FORCEPROP 1 LAST COMMENT_BODY TRUE
J 0
(-3550 3500);
DISPLAY 0.872340 (-3550 3500);
PAINT GREEN (-3550 3500);
DISPLAY INVISIBLE (-3550 3500);
FORCEPROP 2 LAST PATH I23
J 0
(-3625 3675);
DISPLAY 1.021277 (-3625 3675);
DISPLAY INVISIBLE (-3625 3675);
FORCEADD OFFPAGE..1
(-3675 4000);
FORCEPROP 2 LAST $XR1 107 
J 0
(-4016 4000);
DISPLAY 0.638298 (-4016 4000);
PAINT MONO (-4016 4000);
FORCEPROP 2 LAST $XR0 55 
J 0
(-3896 4000);
DISPLAY 0.638298 (-3896 4000);
PAINT MONO (-3896 4000);
FORCEPROP 2 LAST CDS_LIB standard
J 0
(-3675 4000);
PAINT MONO (-3675 4000);
DISPLAY INVISIBLE (-3675 4000);
FORCEPROP 1 LAST OFFPAGE TRUE
J 0
(-3350 3875);
DISPLAY 0.872340 (-3350 3875);
DISPLAY INVISIBLE (-3350 3875);
FORCEPROP 1 LAST COMMENT_BODY TRUE
J 0
(-3550 3900);
DISPLAY 0.872340 (-3550 3900);
PAINT GREEN (-3550 3900);
DISPLAY INVISIBLE (-3550 3900);
FORCEPROP 2 LAST PATH I24
J 0
(-3625 4075);
DISPLAY 1.021277 (-3625 4075);
DISPLAY INVISIBLE (-3625 4075);
FORCEADD TAP..1
R 2
(-2750 1925);
FORCEPROP 3 LASTPIN (-2700 1925) SIG_NAME M_E_CPU1_SB_CB<3>
J 0
(-2690 1935);
DISPLAY 0.659574 (-2690 1935);
PAINT MONO (-2690 1935);
DISPLAY INVISIBLE (-2690 1935);
FORCEPROP 1 LASTPIN (-2700 1925) BN 3
J 2
(-2688 1933);
DISPLAY 0.680851 (-2688 1933);
PAINT GREEN (-2688 1933);
FORCEPROP 2 LAST CDS_LIB standard
J 0
(-2750 1925);
DISPLAY INVISIBLE (-2750 1925);
FORCEPROP 1 LAST BODY_TYPE PLUMBING
J 2
(-2750 1975);
DISPLAY 0.872340 (-2750 1975);
PAINT GREEN (-2750 1975);
DISPLAY INVISIBLE (-2750 1975);
FORCEPROP 1 LAST HDL_TAP TRUE
J 2
(-3075 1800);
DISPLAY 0.872340 (-3075 1800);
DISPLAY INVISIBLE (-3075 1800);
FORCEPROP 1 LAST PATH I26
J 2
(-2748 1925);
DISPLAY 0.872340 (-2748 1925);
PAINT GREEN (-2748 1925);
DISPLAY INVISIBLE (-2748 1925);
FORCEADD TAP..1
R 2
(-2750 1875);
FORCEPROP 3 LASTPIN (-2700 1875) SIG_NAME M_E_CPU1_SB_CB<2>
J 0
(-2690 1885);
DISPLAY 0.659574 (-2690 1885);
PAINT MONO (-2690 1885);
DISPLAY INVISIBLE (-2690 1885);
FORCEPROP 1 LASTPIN (-2700 1875) BN 2
J 2
(-2688 1883);
DISPLAY 0.680851 (-2688 1883);
PAINT GREEN (-2688 1883);
FORCEPROP 2 LAST CDS_LIB standard
J 0
(-2750 1875);
DISPLAY INVISIBLE (-2750 1875);
FORCEPROP 1 LAST BODY_TYPE PLUMBING
J 2
(-2750 1925);
DISPLAY 0.872340 (-2750 1925);
PAINT GREEN (-2750 1925);
DISPLAY INVISIBLE (-2750 1925);
FORCEPROP 1 LAST HDL_TAP TRUE
J 2
(-3075 1750);
DISPLAY 0.872340 (-3075 1750);
DISPLAY INVISIBLE (-3075 1750);
FORCEPROP 1 LAST PATH I27
J 2
(-2748 1875);
DISPLAY 0.872340 (-2748 1875);
PAINT GREEN (-2748 1875);
DISPLAY INVISIBLE (-2748 1875);
FORCEADD TAP..1
R 2
(-2750 1775);
FORCEPROP 3 LASTPIN (-2700 1775) SIG_NAME M_E_CPU1_SB_CB<0>
J 0
(-2690 1785);
DISPLAY 0.659574 (-2690 1785);
PAINT MONO (-2690 1785);
DISPLAY INVISIBLE (-2690 1785);
FORCEPROP 1 LASTPIN (-2700 1775) BN 0
J 2
(-2688 1783);
DISPLAY 0.680851 (-2688 1783);
PAINT GREEN (-2688 1783);
FORCEPROP 2 LAST CDS_LIB standard
J 0
(-2750 1775);
PAINT MONO (-2750 1775);
DISPLAY INVISIBLE (-2750 1775);
FORCEPROP 1 LAST BODY_TYPE PLUMBING
J 2
(-2750 1825);
DISPLAY 0.872340 (-2750 1825);
PAINT GREEN (-2750 1825);
DISPLAY INVISIBLE (-2750 1825);
FORCEPROP 1 LAST HDL_TAP TRUE
J 2
(-3075 1650);
DISPLAY 0.872340 (-3075 1650);
DISPLAY INVISIBLE (-3075 1650);
FORCEPROP 1 LAST PATH I28
J 2
(-2748 1775);
DISPLAY 0.872340 (-2748 1775);
PAINT GREEN (-2748 1775);
DISPLAY INVISIBLE (-2748 1775);
FORCEADD TAP..1
R 2
(-2750 1825);
FORCEPROP 3 LASTPIN (-2700 1825) SIG_NAME M_E_CPU1_SB_CB<1>
J 0
(-2690 1835);
DISPLAY 0.659574 (-2690 1835);
PAINT MONO (-2690 1835);
DISPLAY INVISIBLE (-2690 1835);
FORCEPROP 1 LASTPIN (-2700 1825) BN 1
J 2
(-2688 1833);
DISPLAY 0.680851 (-2688 1833);
PAINT GREEN (-2688 1833);
FORCEPROP 2 LAST CDS_LIB standard
J 0
(-2750 1825);
DISPLAY INVISIBLE (-2750 1825);
FORCEPROP 1 LAST BODY_TYPE PLUMBING
J 2
(-2750 1875);
DISPLAY 0.872340 (-2750 1875);
PAINT GREEN (-2750 1875);
DISPLAY INVISIBLE (-2750 1875);
FORCEPROP 1 LAST HDL_TAP TRUE
J 2
(-3075 1700);
DISPLAY 0.872340 (-3075 1700);
DISPLAY INVISIBLE (-3075 1700);
FORCEPROP 1 LAST PATH I29
J 2
(-2748 1825);
DISPLAY 0.872340 (-2748 1825);
PAINT GREEN (-2748 1825);
DISPLAY INVISIBLE (-2748 1825);
FORCEADD OFFPAGE..2
R 2
(-3675 25);
FORCEPROP 2 LAST $XR0 106 
J 0
(-3930 25);
DISPLAY 0.638298 (-3930 25);
PAINT MONO (-3930 25);
FORCEPROP 2 LAST CDS_LIB standard
J 0
(-3675 25);
PAINT MONO (-3675 25);
DISPLAY INVISIBLE (-3675 25);
FORCEPROP 1 LAST OFFPAGE TRUE
J 2
(-4000 -100);
DISPLAY 0.872340 (-4000 -100);
DISPLAY INVISIBLE (-4000 -100);
FORCEPROP 1 LAST COMMENT_BODY TRUE
J 2
(-3630 -70);
DISPLAY 0.872340 (-3630 -70);
PAINT GREEN (-3630 -70);
DISPLAY INVISIBLE (-3630 -70);
FORCEPROP 2 LAST PATH I3
J 0
(-3625 100);
DISPLAY 1.021277 (-3625 100);
DISPLAY INVISIBLE (-3625 100);
FORCEADD TAP..1
R 2
(-2750 1975);
FORCEPROP 3 LASTPIN (-2700 1975) SIG_NAME M_E_CPU1_SB_CB<4>
J 0
(-2690 1985);
DISPLAY 0.659574 (-2690 1985);
PAINT MONO (-2690 1985);
DISPLAY INVISIBLE (-2690 1985);
FORCEPROP 1 LASTPIN (-2700 1975) BN 4
J 2
(-2688 1983);
DISPLAY 0.680851 (-2688 1983);
PAINT GREEN (-2688 1983);
FORCEPROP 2 LAST CDS_LIB standard
J 0
(-2750 1975);
DISPLAY INVISIBLE (-2750 1975);
FORCEPROP 1 LAST BODY_TYPE PLUMBING
J 2
(-2750 2025);
DISPLAY 0.872340 (-2750 2025);
PAINT GREEN (-2750 2025);
DISPLAY INVISIBLE (-2750 2025);
FORCEPROP 1 LAST HDL_TAP TRUE
J 2
(-3075 1850);
DISPLAY 0.872340 (-3075 1850);
DISPLAY INVISIBLE (-3075 1850);
FORCEPROP 1 LAST PATH I30
J 2
(-2748 1975);
DISPLAY 0.872340 (-2748 1975);
PAINT GREEN (-2748 1975);
DISPLAY INVISIBLE (-2748 1975);
FORCEADD TAP..1
(-1100 825);
FORCEPROP 3 LASTPIN (-1150 825) SIG_NAME M_E_CPU1_SB_DQ<1>
J 0
(-1140 835);
DISPLAY 0.659574 (-1140 835);
PAINT MONO (-1140 835);
DISPLAY INVISIBLE (-1140 835);
FORCEPROP 1 LASTPIN (-1150 825) BN 1
J 0
(-1162 833);
DISPLAY 0.680851 (-1162 833);
PAINT GREEN (-1162 833);
FORCEPROP 2 LAST CDS_LIB standard
J 0
(-1100 825);
PAINT MONO (-1100 825);
DISPLAY INVISIBLE (-1100 825);
FORCEPROP 1 LAST BODY_TYPE PLUMBING
J 0
(-1100 875);
DISPLAY 0.872340 (-1100 875);
PAINT GREEN (-1100 875);
DISPLAY INVISIBLE (-1100 875);
FORCEPROP 1 LAST HDL_TAP TRUE
J 0
(-775 700);
DISPLAY 0.872340 (-775 700);
DISPLAY INVISIBLE (-775 700);
FORCEPROP 1 LAST PATH I31
J 0
(-1102 825);
DISPLAY 0.872340 (-1102 825);
PAINT GREEN (-1102 825);
DISPLAY INVISIBLE (-1102 825);
FORCEADD TAP..1
(-1100 775);
FORCEPROP 3 LASTPIN (-1150 775) SIG_NAME M_E_CPU1_SB_DQ<0>
J 0
(-1140 785);
DISPLAY 0.659574 (-1140 785);
PAINT MONO (-1140 785);
DISPLAY INVISIBLE (-1140 785);
FORCEPROP 1 LASTPIN (-1150 775) BN 0
J 0
(-1162 783);
DISPLAY 0.680851 (-1162 783);
PAINT GREEN (-1162 783);
FORCEPROP 2 LAST CDS_LIB standard
J 0
(-1100 775);
PAINT MONO (-1100 775);
DISPLAY INVISIBLE (-1100 775);
FORCEPROP 1 LAST BODY_TYPE PLUMBING
J 0
(-1100 825);
DISPLAY 0.872340 (-1100 825);
PAINT GREEN (-1100 825);
DISPLAY INVISIBLE (-1100 825);
FORCEPROP 1 LAST HDL_TAP TRUE
J 0
(-775 650);
DISPLAY 0.872340 (-775 650);
DISPLAY INVISIBLE (-775 650);
FORCEPROP 1 LAST PATH I32
J 0
(-1102 775);
DISPLAY 0.872340 (-1102 775);
PAINT GREEN (-1102 775);
DISPLAY INVISIBLE (-1102 775);
FORCEADD TAP..1
(-1100 875);
FORCEPROP 3 LASTPIN (-1150 875) SIG_NAME M_E_CPU1_SB_DQ<2>
J 0
(-1140 885);
DISPLAY 0.659574 (-1140 885);
PAINT MONO (-1140 885);
DISPLAY INVISIBLE (-1140 885);
FORCEPROP 1 LASTPIN (-1150 875) BN 2
J 0
(-1162 883);
DISPLAY 0.680851 (-1162 883);
PAINT GREEN (-1162 883);
FORCEPROP 2 LAST CDS_LIB standard
J 0
(-1100 875);
PAINT MONO (-1100 875);
DISPLAY INVISIBLE (-1100 875);
FORCEPROP 1 LAST BODY_TYPE PLUMBING
J 0
(-1100 925);
DISPLAY 0.872340 (-1100 925);
PAINT GREEN (-1100 925);
DISPLAY INVISIBLE (-1100 925);
FORCEPROP 1 LAST HDL_TAP TRUE
J 0
(-775 750);
DISPLAY 0.872340 (-775 750);
DISPLAY INVISIBLE (-775 750);
FORCEPROP 1 LAST PATH I33
J 0
(-1102 875);
DISPLAY 0.872340 (-1102 875);
PAINT GREEN (-1102 875);
DISPLAY INVISIBLE (-1102 875);
FORCEADD TAP..1
(-1100 925);
FORCEPROP 3 LASTPIN (-1150 925) SIG_NAME M_E_CPU1_SB_DQ<3>
J 0
(-1140 935);
DISPLAY 0.659574 (-1140 935);
PAINT MONO (-1140 935);
DISPLAY INVISIBLE (-1140 935);
FORCEPROP 1 LASTPIN (-1150 925) BN 3
J 0
(-1162 933);
DISPLAY 0.680851 (-1162 933);
PAINT GREEN (-1162 933);
FORCEPROP 2 LAST CDS_LIB standard
J 0
(-1100 925);
PAINT MONO (-1100 925);
DISPLAY INVISIBLE (-1100 925);
FORCEPROP 1 LAST BODY_TYPE PLUMBING
J 0
(-1100 975);
DISPLAY 0.872340 (-1100 975);
PAINT GREEN (-1100 975);
DISPLAY INVISIBLE (-1100 975);
FORCEPROP 1 LAST HDL_TAP TRUE
J 0
(-775 800);
DISPLAY 0.872340 (-775 800);
DISPLAY INVISIBLE (-775 800);
FORCEPROP 1 LAST PATH I34
J 0
(-1102 925);
DISPLAY 0.872340 (-1102 925);
PAINT GREEN (-1102 925);
DISPLAY INVISIBLE (-1102 925);
FORCEADD TAP..1
(-1100 975);
FORCEPROP 3 LASTPIN (-1150 975) SIG_NAME M_E_CPU1_SB_DQ<4>
J 0
(-1140 985);
DISPLAY 0.659574 (-1140 985);
PAINT MONO (-1140 985);
DISPLAY INVISIBLE (-1140 985);
FORCEPROP 1 LASTPIN (-1150 975) BN 4
J 0
(-1162 983);
DISPLAY 0.680851 (-1162 983);
PAINT GREEN (-1162 983);
FORCEPROP 2 LAST CDS_LIB standard
J 0
(-1100 975);
PAINT MONO (-1100 975);
DISPLAY INVISIBLE (-1100 975);
FORCEPROP 1 LAST BODY_TYPE PLUMBING
J 0
(-1100 1025);
DISPLAY 0.872340 (-1100 1025);
PAINT GREEN (-1100 1025);
DISPLAY INVISIBLE (-1100 1025);
FORCEPROP 1 LAST HDL_TAP TRUE
J 0
(-775 850);
DISPLAY 0.872340 (-775 850);
DISPLAY INVISIBLE (-775 850);
FORCEPROP 1 LAST PATH I35
J 0
(-1102 975);
DISPLAY 0.872340 (-1102 975);
PAINT GREEN (-1102 975);
DISPLAY INVISIBLE (-1102 975);
FORCEADD TAP..1
(-1100 1025);
FORCEPROP 3 LASTPIN (-1150 1025) SIG_NAME M_E_CPU1_SB_DQ<5>
J 0
(-1140 1035);
DISPLAY 0.659574 (-1140 1035);
PAINT MONO (-1140 1035);
DISPLAY INVISIBLE (-1140 1035);
FORCEPROP 1 LASTPIN (-1150 1025) BN 5
J 0
(-1162 1033);
DISPLAY 0.680851 (-1162 1033);
PAINT GREEN (-1162 1033);
FORCEPROP 2 LAST CDS_LIB standard
J 0
(-1100 1025);
PAINT MONO (-1100 1025);
DISPLAY INVISIBLE (-1100 1025);
FORCEPROP 1 LAST BODY_TYPE PLUMBING
J 0
(-1100 1075);
DISPLAY 0.872340 (-1100 1075);
PAINT GREEN (-1100 1075);
DISPLAY INVISIBLE (-1100 1075);
FORCEPROP 1 LAST HDL_TAP TRUE
J 0
(-775 900);
DISPLAY 0.872340 (-775 900);
DISPLAY INVISIBLE (-775 900);
FORCEPROP 1 LAST PATH I36
J 0
(-1102 1025);
DISPLAY 0.872340 (-1102 1025);
PAINT GREEN (-1102 1025);
DISPLAY INVISIBLE (-1102 1025);
FORCEADD TAP..1
(-1100 1075);
FORCEPROP 3 LASTPIN (-1150 1075) SIG_NAME M_E_CPU1_SB_DQ<6>
J 0
(-1140 1085);
DISPLAY 0.659574 (-1140 1085);
PAINT MONO (-1140 1085);
DISPLAY INVISIBLE (-1140 1085);
FORCEPROP 1 LASTPIN (-1150 1075) BN 6
J 0
(-1162 1083);
DISPLAY 0.680851 (-1162 1083);
PAINT GREEN (-1162 1083);
FORCEPROP 2 LAST CDS_LIB standard
J 0
(-1100 1075);
PAINT MONO (-1100 1075);
DISPLAY INVISIBLE (-1100 1075);
FORCEPROP 1 LAST BODY_TYPE PLUMBING
J 0
(-1100 1125);
DISPLAY 0.872340 (-1100 1125);
PAINT GREEN (-1100 1125);
DISPLAY INVISIBLE (-1100 1125);
FORCEPROP 1 LAST HDL_TAP TRUE
J 0
(-775 950);
DISPLAY 0.872340 (-775 950);
DISPLAY INVISIBLE (-775 950);
FORCEPROP 1 LAST PATH I37
J 0
(-1102 1075);
DISPLAY 0.872340 (-1102 1075);
PAINT GREEN (-1102 1075);
DISPLAY INVISIBLE (-1102 1075);
FORCEADD TAP..1
(-1100 1225);
FORCEPROP 3 LASTPIN (-1150 1225) SIG_NAME M_E_CPU1_SB_DQ<9>
J 0
(-1140 1235);
DISPLAY 0.659574 (-1140 1235);
PAINT MONO (-1140 1235);
DISPLAY INVISIBLE (-1140 1235);
FORCEPROP 1 LASTPIN (-1150 1225) BN 9
J 0
(-1162 1233);
DISPLAY 0.680851 (-1162 1233);
PAINT GREEN (-1162 1233);
FORCEPROP 2 LAST CDS_LIB standard
J 0
(-1100 1225);
PAINT MONO (-1100 1225);
DISPLAY INVISIBLE (-1100 1225);
FORCEPROP 1 LAST BODY_TYPE PLUMBING
J 0
(-1100 1275);
DISPLAY 0.872340 (-1100 1275);
PAINT GREEN (-1100 1275);
DISPLAY INVISIBLE (-1100 1275);
FORCEPROP 1 LAST HDL_TAP TRUE
J 0
(-775 1100);
DISPLAY 0.872340 (-775 1100);
DISPLAY INVISIBLE (-775 1100);
FORCEPROP 1 LAST PATH I38
J 0
(-1102 1225);
DISPLAY 0.872340 (-1102 1225);
PAINT GREEN (-1102 1225);
DISPLAY INVISIBLE (-1102 1225);
FORCEADD TAP..1
(-1100 1175);
FORCEPROP 3 LASTPIN (-1150 1175) SIG_NAME M_E_CPU1_SB_DQ<8>
J 0
(-1140 1185);
DISPLAY 0.659574 (-1140 1185);
PAINT MONO (-1140 1185);
DISPLAY INVISIBLE (-1140 1185);
FORCEPROP 1 LASTPIN (-1150 1175) BN 8
J 0
(-1162 1183);
DISPLAY 0.680851 (-1162 1183);
PAINT GREEN (-1162 1183);
FORCEPROP 2 LAST CDS_LIB standard
J 0
(-1100 1175);
PAINT MONO (-1100 1175);
DISPLAY INVISIBLE (-1100 1175);
FORCEPROP 1 LAST BODY_TYPE PLUMBING
J 0
(-1100 1225);
DISPLAY 0.872340 (-1100 1225);
PAINT GREEN (-1100 1225);
DISPLAY INVISIBLE (-1100 1225);
FORCEPROP 1 LAST HDL_TAP TRUE
J 0
(-775 1050);
DISPLAY 0.872340 (-775 1050);
DISPLAY INVISIBLE (-775 1050);
FORCEPROP 1 LAST PATH I39
J 0
(-1102 1175);
DISPLAY 0.872340 (-1102 1175);
PAINT GREEN (-1102 1175);
DISPLAY INVISIBLE (-1102 1175);
FORCEADD OFFPAGE..2
R 2
(-3675 575);
FORCEPROP 2 LAST $XR0 55 
J 0
(-3899 575);
DISPLAY 0.638298 (-3899 575);
PAINT MONO (-3899 575);
FORCEPROP 2 LAST CDS_LIB standard
J 0
(-3675 575);
PAINT MONO (-3675 575);
DISPLAY INVISIBLE (-3675 575);
FORCEPROP 1 LAST OFFPAGE TRUE
J 2
(-4000 450);
DISPLAY 0.872340 (-4000 450);
DISPLAY INVISIBLE (-4000 450);
FORCEPROP 1 LAST COMMENT_BODY TRUE
J 2
(-3630 480);
DISPLAY 0.872340 (-3630 480);
PAINT GREEN (-3630 480);
DISPLAY INVISIBLE (-3630 480);
FORCEPROP 2 LAST PATH I4
J 0
(-3625 650);
DISPLAY 1.021277 (-3625 650);
DISPLAY INVISIBLE (-3625 650);
FORCEADD TAP..1
(-1100 1125);
FORCEPROP 3 LASTPIN (-1150 1125) SIG_NAME M_E_CPU1_SB_DQ<7>
J 0
(-1140 1135);
DISPLAY 0.659574 (-1140 1135);
PAINT MONO (-1140 1135);
DISPLAY INVISIBLE (-1140 1135);
FORCEPROP 1 LASTPIN (-1150 1125) BN 7
J 0
(-1162 1133);
DISPLAY 0.680851 (-1162 1133);
PAINT GREEN (-1162 1133);
FORCEPROP 2 LAST CDS_LIB standard
J 0
(-1100 1125);
PAINT MONO (-1100 1125);
DISPLAY INVISIBLE (-1100 1125);
FORCEPROP 1 LAST BODY_TYPE PLUMBING
J 0
(-1100 1175);
DISPLAY 0.872340 (-1100 1175);
PAINT GREEN (-1100 1175);
DISPLAY INVISIBLE (-1100 1175);
FORCEPROP 1 LAST HDL_TAP TRUE
J 0
(-775 1000);
DISPLAY 0.872340 (-775 1000);
DISPLAY INVISIBLE (-775 1000);
FORCEPROP 1 LAST PATH I40
J 0
(-1102 1125);
DISPLAY 0.872340 (-1102 1125);
PAINT GREEN (-1102 1125);
DISPLAY INVISIBLE (-1102 1125);
FORCEADD TAP..1
(-1100 1325);
FORCEPROP 3 LASTPIN (-1150 1325) SIG_NAME M_E_CPU1_SB_DQ<11>
J 0
(-1140 1335);
DISPLAY 0.659574 (-1140 1335);
PAINT MONO (-1140 1335);
DISPLAY INVISIBLE (-1140 1335);
FORCEPROP 1 LASTPIN (-1150 1325) BN 11
J 0
(-1162 1333);
DISPLAY 0.680851 (-1162 1333);
PAINT GREEN (-1162 1333);
FORCEPROP 2 LAST CDS_LIB standard
J 0
(-1100 1325);
PAINT MONO (-1100 1325);
DISPLAY INVISIBLE (-1100 1325);
FORCEPROP 1 LAST BODY_TYPE PLUMBING
J 0
(-1100 1375);
DISPLAY 0.872340 (-1100 1375);
PAINT GREEN (-1100 1375);
DISPLAY INVISIBLE (-1100 1375);
FORCEPROP 1 LAST HDL_TAP TRUE
J 0
(-775 1200);
DISPLAY 0.872340 (-775 1200);
DISPLAY INVISIBLE (-775 1200);
FORCEPROP 1 LAST PATH I41
J 0
(-1102 1325);
DISPLAY 0.872340 (-1102 1325);
PAINT GREEN (-1102 1325);
DISPLAY INVISIBLE (-1102 1325);
FORCEADD TAP..1
(-1100 1275);
FORCEPROP 3 LASTPIN (-1150 1275) SIG_NAME M_E_CPU1_SB_DQ<10>
J 0
(-1140 1285);
DISPLAY 0.659574 (-1140 1285);
PAINT MONO (-1140 1285);
DISPLAY INVISIBLE (-1140 1285);
FORCEPROP 1 LASTPIN (-1150 1275) BN 10
J 0
(-1162 1283);
DISPLAY 0.680851 (-1162 1283);
PAINT GREEN (-1162 1283);
FORCEPROP 2 LAST CDS_LIB standard
J 0
(-1100 1275);
PAINT MONO (-1100 1275);
DISPLAY INVISIBLE (-1100 1275);
FORCEPROP 1 LAST BODY_TYPE PLUMBING
J 0
(-1100 1325);
DISPLAY 0.872340 (-1100 1325);
PAINT GREEN (-1100 1325);
DISPLAY INVISIBLE (-1100 1325);
FORCEPROP 1 LAST HDL_TAP TRUE
J 0
(-775 1150);
DISPLAY 0.872340 (-775 1150);
DISPLAY INVISIBLE (-775 1150);
FORCEPROP 1 LAST PATH I42
J 0
(-1102 1275);
DISPLAY 0.872340 (-1102 1275);
PAINT GREEN (-1102 1275);
DISPLAY INVISIBLE (-1102 1275);
FORCEADD TAP..1
(-1100 1475);
FORCEPROP 3 LASTPIN (-1150 1475) SIG_NAME M_E_CPU1_SB_DQ<14>
J 0
(-1140 1485);
DISPLAY 0.659574 (-1140 1485);
PAINT MONO (-1140 1485);
DISPLAY INVISIBLE (-1140 1485);
FORCEPROP 1 LASTPIN (-1150 1475) BN 14
J 0
(-1162 1483);
DISPLAY 0.680851 (-1162 1483);
PAINT GREEN (-1162 1483);
FORCEPROP 2 LAST CDS_LIB standard
J 0
(-1100 1475);
PAINT MONO (-1100 1475);
DISPLAY INVISIBLE (-1100 1475);
FORCEPROP 1 LAST BODY_TYPE PLUMBING
J 0
(-1100 1525);
DISPLAY 0.872340 (-1100 1525);
PAINT GREEN (-1100 1525);
DISPLAY INVISIBLE (-1100 1525);
FORCEPROP 1 LAST HDL_TAP TRUE
J 0
(-775 1350);
DISPLAY 0.872340 (-775 1350);
DISPLAY INVISIBLE (-775 1350);
FORCEPROP 1 LAST PATH I43
J 0
(-1102 1475);
DISPLAY 0.872340 (-1102 1475);
PAINT GREEN (-1102 1475);
DISPLAY INVISIBLE (-1102 1475);
FORCEADD TAP..1
(-1100 1425);
FORCEPROP 3 LASTPIN (-1150 1425) SIG_NAME M_E_CPU1_SB_DQ<13>
J 0
(-1140 1435);
DISPLAY 0.659574 (-1140 1435);
PAINT MONO (-1140 1435);
DISPLAY INVISIBLE (-1140 1435);
FORCEPROP 1 LASTPIN (-1150 1425) BN 13
J 0
(-1162 1433);
DISPLAY 0.680851 (-1162 1433);
PAINT GREEN (-1162 1433);
FORCEPROP 2 LAST CDS_LIB standard
J 0
(-1100 1425);
PAINT MONO (-1100 1425);
DISPLAY INVISIBLE (-1100 1425);
FORCEPROP 1 LAST BODY_TYPE PLUMBING
J 0
(-1100 1475);
DISPLAY 0.872340 (-1100 1475);
PAINT GREEN (-1100 1475);
DISPLAY INVISIBLE (-1100 1475);
FORCEPROP 1 LAST HDL_TAP TRUE
J 0
(-775 1300);
DISPLAY 0.872340 (-775 1300);
DISPLAY INVISIBLE (-775 1300);
FORCEPROP 1 LAST PATH I44
J 0
(-1102 1425);
DISPLAY 0.872340 (-1102 1425);
PAINT GREEN (-1102 1425);
DISPLAY INVISIBLE (-1102 1425);
FORCEADD TAP..1
(-1100 1375);
FORCEPROP 3 LASTPIN (-1150 1375) SIG_NAME M_E_CPU1_SB_DQ<12>
J 0
(-1140 1385);
DISPLAY 0.659574 (-1140 1385);
PAINT MONO (-1140 1385);
DISPLAY INVISIBLE (-1140 1385);
FORCEPROP 1 LASTPIN (-1150 1375) BN 12
J 0
(-1162 1383);
DISPLAY 0.680851 (-1162 1383);
PAINT GREEN (-1162 1383);
FORCEPROP 2 LAST CDS_LIB standard
J 0
(-1100 1375);
PAINT MONO (-1100 1375);
DISPLAY INVISIBLE (-1100 1375);
FORCEPROP 1 LAST BODY_TYPE PLUMBING
J 0
(-1100 1425);
DISPLAY 0.872340 (-1100 1425);
PAINT GREEN (-1100 1425);
DISPLAY INVISIBLE (-1100 1425);
FORCEPROP 1 LAST HDL_TAP TRUE
J 0
(-775 1250);
DISPLAY 0.872340 (-775 1250);
DISPLAY INVISIBLE (-775 1250);
FORCEPROP 1 LAST PATH I45
J 0
(-1102 1375);
DISPLAY 0.872340 (-1102 1375);
PAINT GREEN (-1102 1375);
DISPLAY INVISIBLE (-1102 1375);
FORCEADD TAP..1
(-1100 1575);
FORCEPROP 3 LASTPIN (-1150 1575) SIG_NAME M_E_CPU1_SB_DQ<16>
J 0
(-1140 1585);
DISPLAY 0.659574 (-1140 1585);
PAINT MONO (-1140 1585);
DISPLAY INVISIBLE (-1140 1585);
FORCEPROP 1 LASTPIN (-1150 1575) BN 16
J 0
(-1162 1583);
DISPLAY 0.680851 (-1162 1583);
PAINT GREEN (-1162 1583);
FORCEPROP 2 LAST CDS_LIB standard
J 0
(-1100 1575);
PAINT MONO (-1100 1575);
DISPLAY INVISIBLE (-1100 1575);
FORCEPROP 1 LAST BODY_TYPE PLUMBING
J 0
(-1100 1625);
DISPLAY 0.872340 (-1100 1625);
PAINT GREEN (-1100 1625);
DISPLAY INVISIBLE (-1100 1625);
FORCEPROP 1 LAST HDL_TAP TRUE
J 0
(-775 1450);
DISPLAY 0.872340 (-775 1450);
DISPLAY INVISIBLE (-775 1450);
FORCEPROP 1 LAST PATH I46
J 0
(-1102 1575);
DISPLAY 0.872340 (-1102 1575);
PAINT GREEN (-1102 1575);
DISPLAY INVISIBLE (-1102 1575);
FORCEADD TAP..1
(-1100 1525);
FORCEPROP 3 LASTPIN (-1150 1525) SIG_NAME M_E_CPU1_SB_DQ<15>
J 0
(-1140 1535);
DISPLAY 0.659574 (-1140 1535);
PAINT MONO (-1140 1535);
DISPLAY INVISIBLE (-1140 1535);
FORCEPROP 1 LASTPIN (-1150 1525) BN 15
J 0
(-1162 1533);
DISPLAY 0.680851 (-1162 1533);
PAINT GREEN (-1162 1533);
FORCEPROP 2 LAST CDS_LIB standard
J 0
(-1100 1525);
PAINT MONO (-1100 1525);
DISPLAY INVISIBLE (-1100 1525);
FORCEPROP 1 LAST BODY_TYPE PLUMBING
J 0
(-1100 1575);
DISPLAY 0.872340 (-1100 1575);
PAINT GREEN (-1100 1575);
DISPLAY INVISIBLE (-1100 1575);
FORCEPROP 1 LAST HDL_TAP TRUE
J 0
(-775 1400);
DISPLAY 0.872340 (-775 1400);
DISPLAY INVISIBLE (-775 1400);
FORCEPROP 1 LAST PATH I47
J 0
(-1102 1525);
DISPLAY 0.872340 (-1102 1525);
PAINT GREEN (-1102 1525);
DISPLAY INVISIBLE (-1102 1525);
FORCEADD TAP..1
(-1100 1725);
FORCEPROP 3 LASTPIN (-1150 1725) SIG_NAME M_E_CPU1_SB_DQ<19>
J 0
(-1140 1735);
DISPLAY 0.659574 (-1140 1735);
PAINT MONO (-1140 1735);
DISPLAY INVISIBLE (-1140 1735);
FORCEPROP 1 LASTPIN (-1150 1725) BN 19
J 0
(-1162 1733);
DISPLAY 0.680851 (-1162 1733);
PAINT GREEN (-1162 1733);
FORCEPROP 2 LAST CDS_LIB standard
J 0
(-1100 1725);
PAINT MONO (-1100 1725);
DISPLAY INVISIBLE (-1100 1725);
FORCEPROP 1 LAST BODY_TYPE PLUMBING
J 0
(-1100 1775);
DISPLAY 0.872340 (-1100 1775);
PAINT GREEN (-1100 1775);
DISPLAY INVISIBLE (-1100 1775);
FORCEPROP 1 LAST HDL_TAP TRUE
J 0
(-775 1600);
DISPLAY 0.872340 (-775 1600);
DISPLAY INVISIBLE (-775 1600);
FORCEPROP 1 LAST PATH I48
J 0
(-1102 1725);
DISPLAY 0.872340 (-1102 1725);
PAINT GREEN (-1102 1725);
DISPLAY INVISIBLE (-1102 1725);
FORCEADD TAP..1
(-1100 1675);
FORCEPROP 3 LASTPIN (-1150 1675) SIG_NAME M_E_CPU1_SB_DQ<18>
J 0
(-1140 1685);
DISPLAY 0.659574 (-1140 1685);
PAINT MONO (-1140 1685);
DISPLAY INVISIBLE (-1140 1685);
FORCEPROP 1 LASTPIN (-1150 1675) BN 18
J 0
(-1162 1683);
DISPLAY 0.680851 (-1162 1683);
PAINT GREEN (-1162 1683);
FORCEPROP 2 LAST CDS_LIB standard
J 0
(-1100 1675);
PAINT MONO (-1100 1675);
DISPLAY INVISIBLE (-1100 1675);
FORCEPROP 1 LAST BODY_TYPE PLUMBING
J 0
(-1100 1725);
DISPLAY 0.872340 (-1100 1725);
PAINT GREEN (-1100 1725);
DISPLAY INVISIBLE (-1100 1725);
FORCEPROP 1 LAST HDL_TAP TRUE
J 0
(-775 1550);
DISPLAY 0.872340 (-775 1550);
DISPLAY INVISIBLE (-775 1550);
FORCEPROP 1 LAST PATH I49
J 0
(-1102 1675);
DISPLAY 0.872340 (-1102 1675);
PAINT GREEN (-1102 1675);
DISPLAY INVISIBLE (-1102 1675);
FORCEADD OFFPAGE..2
R 2
(-3675 525);
FORCEPROP 2 LAST $XR0 55 
J 0
(-3899 525);
DISPLAY 0.638298 (-3899 525);
PAINT MONO (-3899 525);
FORCEPROP 2 LAST CDS_LIB standard
J 0
(-3675 525);
PAINT MONO (-3675 525);
DISPLAY INVISIBLE (-3675 525);
FORCEPROP 1 LAST OFFPAGE TRUE
J 2
(-4000 400);
DISPLAY 0.872340 (-4000 400);
DISPLAY INVISIBLE (-4000 400);
FORCEPROP 1 LAST COMMENT_BODY TRUE
J 2
(-3630 430);
DISPLAY 0.872340 (-3630 430);
PAINT GREEN (-3630 430);
DISPLAY INVISIBLE (-3630 430);
FORCEPROP 2 LAST PATH I5
J 0
(-3625 600);
DISPLAY 1.021277 (-3625 600);
DISPLAY INVISIBLE (-3625 600);
FORCEADD TAP..1
(-1100 1625);
FORCEPROP 3 LASTPIN (-1150 1625) SIG_NAME M_E_CPU1_SB_DQ<17>
J 0
(-1140 1635);
DISPLAY 0.659574 (-1140 1635);
PAINT MONO (-1140 1635);
DISPLAY INVISIBLE (-1140 1635);
FORCEPROP 1 LASTPIN (-1150 1625) BN 17
J 0
(-1162 1633);
DISPLAY 0.680851 (-1162 1633);
PAINT GREEN (-1162 1633);
FORCEPROP 2 LAST CDS_LIB standard
J 0
(-1100 1625);
PAINT MONO (-1100 1625);
DISPLAY INVISIBLE (-1100 1625);
FORCEPROP 1 LAST BODY_TYPE PLUMBING
J 0
(-1100 1675);
DISPLAY 0.872340 (-1100 1675);
PAINT GREEN (-1100 1675);
DISPLAY INVISIBLE (-1100 1675);
FORCEPROP 1 LAST HDL_TAP TRUE
J 0
(-775 1500);
DISPLAY 0.872340 (-775 1500);
DISPLAY INVISIBLE (-775 1500);
FORCEPROP 1 LAST PATH I50
J 0
(-1102 1625);
DISPLAY 0.872340 (-1102 1625);
PAINT GREEN (-1102 1625);
DISPLAY INVISIBLE (-1102 1625);
FORCEADD TAP..1
(-1100 1775);
FORCEPROP 3 LASTPIN (-1150 1775) SIG_NAME M_E_CPU1_SB_DQ<20>
J 0
(-1140 1785);
DISPLAY 0.659574 (-1140 1785);
PAINT MONO (-1140 1785);
DISPLAY INVISIBLE (-1140 1785);
FORCEPROP 1 LASTPIN (-1150 1775) BN 20
J 0
(-1162 1783);
DISPLAY 0.680851 (-1162 1783);
PAINT GREEN (-1162 1783);
FORCEPROP 2 LAST CDS_LIB standard
J 0
(-1100 1775);
PAINT MONO (-1100 1775);
DISPLAY INVISIBLE (-1100 1775);
FORCEPROP 1 LAST BODY_TYPE PLUMBING
J 0
(-1100 1825);
DISPLAY 0.872340 (-1100 1825);
PAINT GREEN (-1100 1825);
DISPLAY INVISIBLE (-1100 1825);
FORCEPROP 1 LAST HDL_TAP TRUE
J 0
(-775 1650);
DISPLAY 0.872340 (-775 1650);
DISPLAY INVISIBLE (-775 1650);
FORCEPROP 1 LAST PATH I51
J 0
(-1102 1775);
DISPLAY 0.872340 (-1102 1775);
PAINT GREEN (-1102 1775);
DISPLAY INVISIBLE (-1102 1775);
FORCEADD TAP..1
(-1100 1825);
FORCEPROP 3 LASTPIN (-1150 1825) SIG_NAME M_E_CPU1_SB_DQ<21>
J 0
(-1140 1835);
DISPLAY 0.659574 (-1140 1835);
PAINT MONO (-1140 1835);
DISPLAY INVISIBLE (-1140 1835);
FORCEPROP 1 LASTPIN (-1150 1825) BN 21
J 0
(-1162 1833);
DISPLAY 0.680851 (-1162 1833);
PAINT GREEN (-1162 1833);
FORCEPROP 2 LAST CDS_LIB standard
J 0
(-1100 1825);
PAINT MONO (-1100 1825);
DISPLAY INVISIBLE (-1100 1825);
FORCEPROP 1 LAST BODY_TYPE PLUMBING
J 0
(-1100 1875);
DISPLAY 0.872340 (-1100 1875);
PAINT GREEN (-1100 1875);
DISPLAY INVISIBLE (-1100 1875);
FORCEPROP 1 LAST HDL_TAP TRUE
J 0
(-775 1700);
DISPLAY 0.872340 (-775 1700);
DISPLAY INVISIBLE (-775 1700);
FORCEPROP 1 LAST PATH I52
J 0
(-1102 1825);
DISPLAY 0.872340 (-1102 1825);
PAINT GREEN (-1102 1825);
DISPLAY INVISIBLE (-1102 1825);
FORCEADD TAP..1
(-1100 1875);
FORCEPROP 3 LASTPIN (-1150 1875) SIG_NAME M_E_CPU1_SB_DQ<22>
J 0
(-1140 1885);
DISPLAY 0.659574 (-1140 1885);
PAINT MONO (-1140 1885);
DISPLAY INVISIBLE (-1140 1885);
FORCEPROP 1 LASTPIN (-1150 1875) BN 22
J 0
(-1162 1883);
DISPLAY 0.680851 (-1162 1883);
PAINT GREEN (-1162 1883);
FORCEPROP 2 LAST CDS_LIB standard
J 0
(-1100 1875);
DISPLAY INVISIBLE (-1100 1875);
FORCEPROP 1 LAST BODY_TYPE PLUMBING
J 0
(-1100 1925);
DISPLAY 0.872340 (-1100 1925);
PAINT GREEN (-1100 1925);
DISPLAY INVISIBLE (-1100 1925);
FORCEPROP 1 LAST HDL_TAP TRUE
J 0
(-775 1750);
DISPLAY 0.872340 (-775 1750);
DISPLAY INVISIBLE (-775 1750);
FORCEPROP 1 LAST PATH I53
J 0
(-1102 1875);
DISPLAY 0.872340 (-1102 1875);
PAINT GREEN (-1102 1875);
DISPLAY INVISIBLE (-1102 1875);
FORCEADD TAP..1
(-1100 1975);
FORCEPROP 3 LASTPIN (-1150 1975) SIG_NAME M_E_CPU1_SB_DQ<24>
J 0
(-1140 1985);
DISPLAY 0.659574 (-1140 1985);
PAINT MONO (-1140 1985);
DISPLAY INVISIBLE (-1140 1985);
FORCEPROP 1 LASTPIN (-1150 1975) BN 24
J 0
(-1162 1983);
DISPLAY 0.680851 (-1162 1983);
PAINT GREEN (-1162 1983);
FORCEPROP 2 LAST CDS_LIB standard
J 0
(-1100 1975);
DISPLAY INVISIBLE (-1100 1975);
FORCEPROP 1 LAST BODY_TYPE PLUMBING
J 0
(-1100 2025);
DISPLAY 0.872340 (-1100 2025);
PAINT GREEN (-1100 2025);
DISPLAY INVISIBLE (-1100 2025);
FORCEPROP 1 LAST HDL_TAP TRUE
J 0
(-775 1850);
DISPLAY 0.872340 (-775 1850);
DISPLAY INVISIBLE (-775 1850);
FORCEPROP 1 LAST PATH I54
J 0
(-1102 1975);
DISPLAY 0.872340 (-1102 1975);
PAINT GREEN (-1102 1975);
DISPLAY INVISIBLE (-1102 1975);
FORCEADD TAP..1
(-1100 1925);
FORCEPROP 3 LASTPIN (-1150 1925) SIG_NAME M_E_CPU1_SB_DQ<23>
J 0
(-1140 1935);
DISPLAY 0.659574 (-1140 1935);
PAINT MONO (-1140 1935);
DISPLAY INVISIBLE (-1140 1935);
FORCEPROP 1 LASTPIN (-1150 1925) BN 23
J 0
(-1162 1933);
DISPLAY 0.680851 (-1162 1933);
PAINT GREEN (-1162 1933);
FORCEPROP 2 LAST CDS_LIB standard
J 0
(-1100 1925);
DISPLAY INVISIBLE (-1100 1925);
FORCEPROP 1 LAST BODY_TYPE PLUMBING
J 0
(-1100 1975);
DISPLAY 0.872340 (-1100 1975);
PAINT GREEN (-1100 1975);
DISPLAY INVISIBLE (-1100 1975);
FORCEPROP 1 LAST HDL_TAP TRUE
J 0
(-775 1800);
DISPLAY 0.872340 (-775 1800);
DISPLAY INVISIBLE (-775 1800);
FORCEPROP 1 LAST PATH I55
J 0
(-1102 1925);
DISPLAY 0.872340 (-1102 1925);
PAINT GREEN (-1102 1925);
DISPLAY INVISIBLE (-1102 1925);
FORCEADD TAP..1
R 2
(-2750 2075);
FORCEPROP 3 LASTPIN (-2700 2075) SIG_NAME M_E_CPU1_SB_CB<6>
J 0
(-2690 2085);
DISPLAY 0.659574 (-2690 2085);
PAINT MONO (-2690 2085);
DISPLAY INVISIBLE (-2690 2085);
FORCEPROP 1 LASTPIN (-2700 2075) BN 6
J 2
(-2688 2083);
DISPLAY 0.680851 (-2688 2083);
PAINT GREEN (-2688 2083);
FORCEPROP 2 LAST CDS_LIB standard
J 0
(-2750 2075);
DISPLAY INVISIBLE (-2750 2075);
FORCEPROP 1 LAST BODY_TYPE PLUMBING
J 2
(-2750 2125);
DISPLAY 0.872340 (-2750 2125);
PAINT GREEN (-2750 2125);
DISPLAY INVISIBLE (-2750 2125);
FORCEPROP 1 LAST HDL_TAP TRUE
J 2
(-3075 1950);
DISPLAY 0.872340 (-3075 1950);
DISPLAY INVISIBLE (-3075 1950);
FORCEPROP 1 LAST PATH I56
J 2
(-2748 2075);
DISPLAY 0.872340 (-2748 2075);
PAINT GREEN (-2748 2075);
DISPLAY INVISIBLE (-2748 2075);
FORCEADD TAP..1
R 2
(-2750 2025);
FORCEPROP 3 LASTPIN (-2700 2025) SIG_NAME M_E_CPU1_SB_CB<5>
J 0
(-2690 2035);
DISPLAY 0.659574 (-2690 2035);
PAINT MONO (-2690 2035);
DISPLAY INVISIBLE (-2690 2035);
FORCEPROP 1 LASTPIN (-2700 2025) BN 5
J 2
(-2688 2033);
DISPLAY 0.680851 (-2688 2033);
PAINT GREEN (-2688 2033);
FORCEPROP 2 LAST CDS_LIB standard
J 0
(-2750 2025);
DISPLAY INVISIBLE (-2750 2025);
FORCEPROP 1 LAST BODY_TYPE PLUMBING
J 2
(-2750 2075);
DISPLAY 0.872340 (-2750 2075);
PAINT GREEN (-2750 2075);
DISPLAY INVISIBLE (-2750 2075);
FORCEPROP 1 LAST HDL_TAP TRUE
J 2
(-3075 1900);
DISPLAY 0.872340 (-3075 1900);
DISPLAY INVISIBLE (-3075 1900);
FORCEPROP 1 LAST PATH I57
J 2
(-2748 2025);
DISPLAY 0.872340 (-2748 2025);
PAINT GREEN (-2748 2025);
DISPLAY INVISIBLE (-2748 2025);
FORCEADD TAP..1
R 2
(-2750 2225);
FORCEPROP 3 LASTPIN (-2700 2225) SIG_NAME M_E_CPU1_SA_CB<0>
J 0
(-2690 2235);
DISPLAY 0.659574 (-2690 2235);
PAINT MONO (-2690 2235);
DISPLAY INVISIBLE (-2690 2235);
FORCEPROP 1 LASTPIN (-2700 2225) BN 0
J 2
(-2688 2233);
DISPLAY 0.680851 (-2688 2233);
PAINT GREEN (-2688 2233);
FORCEPROP 2 LAST CDS_LIB standard
J 0
(-2750 2225);
PAINT MONO (-2750 2225);
DISPLAY INVISIBLE (-2750 2225);
FORCEPROP 1 LAST BODY_TYPE PLUMBING
J 2
(-2750 2275);
DISPLAY 0.872340 (-2750 2275);
PAINT GREEN (-2750 2275);
DISPLAY INVISIBLE (-2750 2275);
FORCEPROP 1 LAST HDL_TAP TRUE
J 2
(-3075 2100);
DISPLAY 0.872340 (-3075 2100);
DISPLAY INVISIBLE (-3075 2100);
FORCEPROP 1 LAST PATH I58
J 2
(-2748 2225);
DISPLAY 0.872340 (-2748 2225);
PAINT GREEN (-2748 2225);
DISPLAY INVISIBLE (-2748 2225);
FORCEADD TAP..1
R 2
(-2750 2125);
FORCEPROP 3 LASTPIN (-2700 2125) SIG_NAME M_E_CPU1_SB_CB<7>
J 0
(-2690 2135);
DISPLAY 0.659574 (-2690 2135);
PAINT MONO (-2690 2135);
DISPLAY INVISIBLE (-2690 2135);
FORCEPROP 1 LASTPIN (-2700 2125) BN 7
J 2
(-2688 2133);
DISPLAY 0.680851 (-2688 2133);
PAINT GREEN (-2688 2133);
FORCEPROP 2 LAST CDS_LIB standard
J 0
(-2750 2125);
DISPLAY INVISIBLE (-2750 2125);
FORCEPROP 1 LAST BODY_TYPE PLUMBING
J 2
(-2750 2175);
DISPLAY 0.872340 (-2750 2175);
PAINT GREEN (-2750 2175);
DISPLAY INVISIBLE (-2750 2175);
FORCEPROP 1 LAST HDL_TAP TRUE
J 2
(-3075 2000);
DISPLAY 0.872340 (-3075 2000);
DISPLAY INVISIBLE (-3075 2000);
FORCEPROP 1 LAST PATH I59
J 2
(-2748 2125);
DISPLAY 0.872340 (-2748 2125);
PAINT GREEN (-2748 2125);
DISPLAY INVISIBLE (-2748 2125);
FORCEADD OFFPAGE..3
R 2
(-3675 1125);
FORCEPROP 2 LAST $XR0 114 
J 0
(-3955 1125);
DISPLAY 0.638298 (-3955 1125);
PAINT MONO (-3955 1125);
FORCEPROP 2 LAST CDS_LIB standard
J 0
(-3675 1125);
PAINT MONO (-3675 1125);
DISPLAY INVISIBLE (-3675 1125);
FORCEPROP 1 LAST OFFPAGE TRUE
J 2
(-4000 1000);
DISPLAY 0.872340 (-4000 1000);
DISPLAY INVISIBLE (-4000 1000);
FORCEPROP 1 LAST COMMENT_BODY TRUE
J 2
(-3625 1025);
DISPLAY 0.872340 (-3625 1025);
PAINT GREEN (-3625 1025);
DISPLAY INVISIBLE (-3625 1025);
FORCEPROP 2 LAST PATH I6
J 0
(-3625 1200);
DISPLAY 1.021277 (-3625 1200);
DISPLAY INVISIBLE (-3625 1200);
FORCEADD TAP..1
R 2
(-2750 2275);
FORCEPROP 3 LASTPIN (-2700 2275) SIG_NAME M_E_CPU1_SA_CB<1>
J 0
(-2690 2285);
DISPLAY 0.659574 (-2690 2285);
PAINT MONO (-2690 2285);
DISPLAY INVISIBLE (-2690 2285);
FORCEPROP 1 LASTPIN (-2700 2275) BN 1
J 2
(-2688 2283);
DISPLAY 0.680851 (-2688 2283);
PAINT GREEN (-2688 2283);
FORCEPROP 2 LAST CDS_LIB standard
J 0
(-2750 2275);
DISPLAY INVISIBLE (-2750 2275);
FORCEPROP 1 LAST BODY_TYPE PLUMBING
J 2
(-2750 2325);
DISPLAY 0.872340 (-2750 2325);
PAINT GREEN (-2750 2325);
DISPLAY INVISIBLE (-2750 2325);
FORCEPROP 1 LAST HDL_TAP TRUE
J 2
(-3075 2150);
DISPLAY 0.872340 (-3075 2150);
DISPLAY INVISIBLE (-3075 2150);
FORCEPROP 1 LAST PATH I60
J 2
(-2748 2275);
DISPLAY 0.872340 (-2748 2275);
PAINT GREEN (-2748 2275);
DISPLAY INVISIBLE (-2748 2275);
FORCEADD TAP..1
R 2
(-2750 2325);
FORCEPROP 3 LASTPIN (-2700 2325) SIG_NAME M_E_CPU1_SA_CB<2>
J 0
(-2690 2335);
DISPLAY 0.659574 (-2690 2335);
PAINT MONO (-2690 2335);
DISPLAY INVISIBLE (-2690 2335);
FORCEPROP 1 LASTPIN (-2700 2325) BN 2
J 2
(-2688 2333);
DISPLAY 0.680851 (-2688 2333);
PAINT GREEN (-2688 2333);
FORCEPROP 2 LAST CDS_LIB standard
J 0
(-2750 2325);
DISPLAY INVISIBLE (-2750 2325);
FORCEPROP 1 LAST BODY_TYPE PLUMBING
J 2
(-2750 2375);
DISPLAY 0.872340 (-2750 2375);
PAINT GREEN (-2750 2375);
DISPLAY INVISIBLE (-2750 2375);
FORCEPROP 1 LAST HDL_TAP TRUE
J 2
(-3075 2200);
DISPLAY 0.872340 (-3075 2200);
DISPLAY INVISIBLE (-3075 2200);
FORCEPROP 1 LAST PATH I61
J 2
(-2748 2325);
DISPLAY 0.872340 (-2748 2325);
PAINT GREEN (-2748 2325);
DISPLAY INVISIBLE (-2748 2325);
FORCEADD TAP..1
R 2
(-2750 2375);
FORCEPROP 3 LASTPIN (-2700 2375) SIG_NAME M_E_CPU1_SA_CB<3>
J 0
(-2690 2385);
DISPLAY 0.659574 (-2690 2385);
PAINT MONO (-2690 2385);
DISPLAY INVISIBLE (-2690 2385);
FORCEPROP 1 LASTPIN (-2700 2375) BN 3
J 2
(-2688 2383);
DISPLAY 0.680851 (-2688 2383);
PAINT GREEN (-2688 2383);
FORCEPROP 2 LAST CDS_LIB standard
J 0
(-2750 2375);
DISPLAY INVISIBLE (-2750 2375);
FORCEPROP 1 LAST BODY_TYPE PLUMBING
J 2
(-2750 2425);
DISPLAY 0.872340 (-2750 2425);
PAINT GREEN (-2750 2425);
DISPLAY INVISIBLE (-2750 2425);
FORCEPROP 1 LAST HDL_TAP TRUE
J 2
(-3075 2250);
DISPLAY 0.872340 (-3075 2250);
DISPLAY INVISIBLE (-3075 2250);
FORCEPROP 1 LAST PATH I62
J 2
(-2748 2375);
DISPLAY 0.872340 (-2748 2375);
PAINT GREEN (-2748 2375);
DISPLAY INVISIBLE (-2748 2375);
FORCEADD TAP..1
R 2
(-2750 2475);
FORCEPROP 3 LASTPIN (-2700 2475) SIG_NAME M_E_CPU1_SA_CB<5>
J 0
(-2690 2485);
DISPLAY 0.659574 (-2690 2485);
PAINT MONO (-2690 2485);
DISPLAY INVISIBLE (-2690 2485);
FORCEPROP 1 LASTPIN (-2700 2475) BN 5
J 2
(-2688 2483);
DISPLAY 0.680851 (-2688 2483);
PAINT GREEN (-2688 2483);
FORCEPROP 2 LAST CDS_LIB standard
J 0
(-2750 2475);
DISPLAY INVISIBLE (-2750 2475);
FORCEPROP 1 LAST BODY_TYPE PLUMBING
J 2
(-2750 2525);
DISPLAY 0.872340 (-2750 2525);
PAINT GREEN (-2750 2525);
DISPLAY INVISIBLE (-2750 2525);
FORCEPROP 1 LAST HDL_TAP TRUE
J 2
(-3075 2350);
DISPLAY 0.872340 (-3075 2350);
DISPLAY INVISIBLE (-3075 2350);
FORCEPROP 1 LAST PATH I63
J 2
(-2748 2475);
DISPLAY 0.872340 (-2748 2475);
PAINT GREEN (-2748 2475);
DISPLAY INVISIBLE (-2748 2475);
FORCEADD TAP..1
R 2
(-2750 2425);
FORCEPROP 3 LASTPIN (-2700 2425) SIG_NAME M_E_CPU1_SA_CB<4>
J 0
(-2690 2435);
DISPLAY 0.659574 (-2690 2435);
PAINT MONO (-2690 2435);
DISPLAY INVISIBLE (-2690 2435);
FORCEPROP 1 LASTPIN (-2700 2425) BN 4
J 2
(-2688 2433);
DISPLAY 0.680851 (-2688 2433);
PAINT GREEN (-2688 2433);
FORCEPROP 2 LAST CDS_LIB standard
J 0
(-2750 2425);
DISPLAY INVISIBLE (-2750 2425);
FORCEPROP 1 LAST BODY_TYPE PLUMBING
J 2
(-2750 2475);
DISPLAY 0.872340 (-2750 2475);
PAINT GREEN (-2750 2475);
DISPLAY INVISIBLE (-2750 2475);
FORCEPROP 1 LAST HDL_TAP TRUE
J 2
(-3075 2300);
DISPLAY 0.872340 (-3075 2300);
DISPLAY INVISIBLE (-3075 2300);
FORCEPROP 1 LAST PATH I64
J 2
(-2748 2425);
DISPLAY 0.872340 (-2748 2425);
PAINT GREEN (-2748 2425);
DISPLAY INVISIBLE (-2748 2425);
FORCEADD TAP..1
R 2
(-2750 2575);
FORCEPROP 3 LASTPIN (-2700 2575) SIG_NAME M_E_CPU1_SA_CB<7>
J 0
(-2690 2585);
DISPLAY 0.659574 (-2690 2585);
PAINT MONO (-2690 2585);
DISPLAY INVISIBLE (-2690 2585);
FORCEPROP 1 LASTPIN (-2700 2575) BN 7
J 2
(-2688 2583);
DISPLAY 0.680851 (-2688 2583);
PAINT GREEN (-2688 2583);
FORCEPROP 2 LAST CDS_LIB standard
J 0
(-2750 2575);
DISPLAY INVISIBLE (-2750 2575);
FORCEPROP 1 LAST BODY_TYPE PLUMBING
J 2
(-2750 2625);
DISPLAY 0.872340 (-2750 2625);
PAINT GREEN (-2750 2625);
DISPLAY INVISIBLE (-2750 2625);
FORCEPROP 1 LAST HDL_TAP TRUE
J 2
(-3075 2450);
DISPLAY 0.872340 (-3075 2450);
DISPLAY INVISIBLE (-3075 2450);
FORCEPROP 1 LAST PATH I65
J 2
(-2748 2575);
DISPLAY 0.872340 (-2748 2575);
PAINT GREEN (-2748 2575);
DISPLAY INVISIBLE (-2748 2575);
FORCEADD TAP..1
R 2
(-2750 2525);
FORCEPROP 3 LASTPIN (-2700 2525) SIG_NAME M_E_CPU1_SA_CB<6>
J 0
(-2690 2535);
DISPLAY 0.659574 (-2690 2535);
PAINT MONO (-2690 2535);
DISPLAY INVISIBLE (-2690 2535);
FORCEPROP 1 LASTPIN (-2700 2525) BN 6
J 2
(-2688 2533);
DISPLAY 0.680851 (-2688 2533);
PAINT GREEN (-2688 2533);
FORCEPROP 2 LAST CDS_LIB standard
J 0
(-2750 2525);
DISPLAY INVISIBLE (-2750 2525);
FORCEPROP 1 LAST BODY_TYPE PLUMBING
J 2
(-2750 2575);
DISPLAY 0.872340 (-2750 2575);
PAINT GREEN (-2750 2575);
DISPLAY INVISIBLE (-2750 2575);
FORCEPROP 1 LAST HDL_TAP TRUE
J 2
(-3075 2400);
DISPLAY 0.872340 (-3075 2400);
DISPLAY INVISIBLE (-3075 2400);
FORCEPROP 1 LAST PATH I66
J 2
(-2748 2525);
DISPLAY 0.872340 (-2748 2525);
PAINT GREEN (-2748 2525);
DISPLAY INVISIBLE (-2748 2525);
FORCEADD TAP..1
R 2
(-2750 3275);
FORCEPROP 3 LASTPIN (-2700 3275) SIG_NAME M_E_CPU1_SB_CA<0>
J 0
(-2690 3285);
DISPLAY 0.659574 (-2690 3285);
PAINT MONO (-2690 3285);
DISPLAY INVISIBLE (-2690 3285);
FORCEPROP 1 LASTPIN (-2700 3275) BN 0
J 2
(-2688 3283);
DISPLAY 0.680851 (-2688 3283);
PAINT GREEN (-2688 3283);
FORCEPROP 2 LAST CDS_LIB standard
J 0
(-2750 3275);
DISPLAY INVISIBLE (-2750 3275);
FORCEPROP 1 LAST BODY_TYPE PLUMBING
J 2
(-2750 3325);
DISPLAY 0.872340 (-2750 3325);
PAINT GREEN (-2750 3325);
DISPLAY INVISIBLE (-2750 3325);
FORCEPROP 1 LAST HDL_TAP TRUE
J 2
(-3075 3150);
DISPLAY 0.872340 (-3075 3150);
DISPLAY INVISIBLE (-3075 3150);
FORCEPROP 1 LAST PATH I67
J 2
(-2748 3275);
DISPLAY 0.872340 (-2748 3275);
PAINT GREEN (-2748 3275);
DISPLAY INVISIBLE (-2748 3275);
FORCEADD TAP..1
R 2
(-2750 3325);
FORCEPROP 3 LASTPIN (-2700 3325) SIG_NAME M_E_CPU1_SB_CA<1>
J 0
(-2690 3335);
DISPLAY 0.659574 (-2690 3335);
PAINT MONO (-2690 3335);
DISPLAY INVISIBLE (-2690 3335);
FORCEPROP 1 LASTPIN (-2700 3325) BN 1
J 2
(-2688 3333);
DISPLAY 0.680851 (-2688 3333);
PAINT GREEN (-2688 3333);
FORCEPROP 2 LAST CDS_LIB standard
J 0
(-2750 3325);
DISPLAY INVISIBLE (-2750 3325);
FORCEPROP 1 LAST BODY_TYPE PLUMBING
J 2
(-2750 3375);
DISPLAY 0.872340 (-2750 3375);
PAINT GREEN (-2750 3375);
DISPLAY INVISIBLE (-2750 3375);
FORCEPROP 1 LAST HDL_TAP TRUE
J 2
(-3075 3200);
DISPLAY 0.872340 (-3075 3200);
DISPLAY INVISIBLE (-3075 3200);
FORCEPROP 1 LAST PATH I68
J 2
(-2748 3325);
DISPLAY 0.872340 (-2748 3325);
PAINT GREEN (-2748 3325);
DISPLAY INVISIBLE (-2748 3325);
FORCEADD TAP..1
R 2
(-2750 3375);
FORCEPROP 3 LASTPIN (-2700 3375) SIG_NAME M_E_CPU1_SB_CA<2>
J 0
(-2690 3385);
DISPLAY 0.659574 (-2690 3385);
PAINT MONO (-2690 3385);
DISPLAY INVISIBLE (-2690 3385);
FORCEPROP 1 LASTPIN (-2700 3375) BN 2
J 2
(-2688 3383);
DISPLAY 0.680851 (-2688 3383);
PAINT GREEN (-2688 3383);
FORCEPROP 2 LAST CDS_LIB standard
J 0
(-2750 3375);
DISPLAY INVISIBLE (-2750 3375);
FORCEPROP 1 LAST BODY_TYPE PLUMBING
J 2
(-2750 3425);
DISPLAY 0.872340 (-2750 3425);
PAINT GREEN (-2750 3425);
DISPLAY INVISIBLE (-2750 3425);
FORCEPROP 1 LAST HDL_TAP TRUE
J 2
(-3075 3250);
DISPLAY 0.872340 (-3075 3250);
DISPLAY INVISIBLE (-3075 3250);
FORCEPROP 1 LAST PATH I69
J 2
(-2748 3375);
DISPLAY 0.872340 (-2748 3375);
PAINT GREEN (-2748 3375);
DISPLAY INVISIBLE (-2748 3375);
FORCEADD OFFPAGE..1
(-3600 1425);
FORCEPROP 2 LAST $XR7 113 
J 0
(-4122 1461);
DISPLAY 0.638298 (-4122 1461);
PAINT MONO (-4122 1461);
FORCEPROP 2 LAST $XR6 112 
J 0
(-4002 1461);
DISPLAY 0.638298 (-4002 1461);
PAINT MONO (-4002 1461);
FORCEPROP 2 LAST $XR5 111 
J 0
(-4122 1389);
DISPLAY 0.638298 (-4122 1389);
PAINT MONO (-4122 1389);
FORCEPROP 2 LAST $XR4 110 
J 0
(-4002 1389);
DISPLAY 0.638298 (-4002 1389);
PAINT MONO (-4002 1389);
FORCEPROP 2 LAST $XR3 109 
J 0
(-3882 1389);
DISPLAY 0.638298 (-3882 1389);
PAINT MONO (-3882 1389);
FORCEPROP 2 LAST $XR2 108 
J 0
(-4122 1425);
DISPLAY 0.638298 (-4122 1425);
PAINT MONO (-4122 1425);
FORCEPROP 2 LAST $XR1 107 
J 0
(-4002 1425);
DISPLAY 0.638298 (-4002 1425);
PAINT MONO (-4002 1425);
FORCEPROP 2 LAST $XR0 230 
J 0
(-3882 1425);
DISPLAY 0.638298 (-3882 1425);
PAINT MONO (-3882 1425);
FORCEPROP 2 LAST CDS_LIB standard
J 0
(-3600 1425);
PAINT MONO (-3600 1425);
DISPLAY INVISIBLE (-3600 1425);
FORCEPROP 1 LAST OFFPAGE TRUE
J 0
(-3275 1300);
DISPLAY 0.872340 (-3275 1300);
DISPLAY INVISIBLE (-3275 1300);
FORCEPROP 1 LAST COMMENT_BODY TRUE
J 0
(-3475 1325);
DISPLAY 0.872340 (-3475 1325);
PAINT GREEN (-3475 1325);
DISPLAY INVISIBLE (-3475 1325);
FORCEPROP 2 LAST PATH I7
J 0
(-3550 1500);
DISPLAY 1.021277 (-3550 1500);
DISPLAY INVISIBLE (-3550 1500);
FORCEADD TAP..1
R 2
(-2750 3425);
FORCEPROP 3 LASTPIN (-2700 3425) SIG_NAME M_E_CPU1_SB_CA<3>
J 0
(-2690 3435);
DISPLAY 0.659574 (-2690 3435);
PAINT MONO (-2690 3435);
DISPLAY INVISIBLE (-2690 3435);
FORCEPROP 1 LASTPIN (-2700 3425) BN 3
J 2
(-2688 3433);
DISPLAY 0.680851 (-2688 3433);
PAINT GREEN (-2688 3433);
FORCEPROP 2 LAST CDS_LIB standard
J 0
(-2750 3425);
DISPLAY INVISIBLE (-2750 3425);
FORCEPROP 1 LAST BODY_TYPE PLUMBING
J 2
(-2750 3475);
DISPLAY 0.872340 (-2750 3475);
PAINT GREEN (-2750 3475);
DISPLAY INVISIBLE (-2750 3475);
FORCEPROP 1 LAST HDL_TAP TRUE
J 2
(-3075 3300);
DISPLAY 0.872340 (-3075 3300);
DISPLAY INVISIBLE (-3075 3300);
FORCEPROP 1 LAST PATH I70
J 2
(-2748 3425);
DISPLAY 0.872340 (-2748 3425);
PAINT GREEN (-2748 3425);
DISPLAY INVISIBLE (-2748 3425);
FORCEADD TAP..1
R 2
(-2750 3475);
FORCEPROP 3 LASTPIN (-2700 3475) SIG_NAME M_E_CPU1_SB_CA<4>
J 0
(-2690 3485);
DISPLAY 0.659574 (-2690 3485);
PAINT MONO (-2690 3485);
DISPLAY INVISIBLE (-2690 3485);
FORCEPROP 1 LASTPIN (-2700 3475) BN 4
J 2
(-2688 3483);
DISPLAY 0.680851 (-2688 3483);
PAINT GREEN (-2688 3483);
FORCEPROP 2 LAST CDS_LIB standard
J 0
(-2750 3475);
DISPLAY INVISIBLE (-2750 3475);
FORCEPROP 1 LAST BODY_TYPE PLUMBING
J 2
(-2750 3525);
DISPLAY 0.872340 (-2750 3525);
PAINT GREEN (-2750 3525);
DISPLAY INVISIBLE (-2750 3525);
FORCEPROP 1 LAST HDL_TAP TRUE
J 2
(-3075 3350);
DISPLAY 0.872340 (-3075 3350);
DISPLAY INVISIBLE (-3075 3350);
FORCEPROP 1 LAST PATH I71
J 2
(-2748 3475);
DISPLAY 0.872340 (-2748 3475);
PAINT GREEN (-2748 3475);
DISPLAY INVISIBLE (-2748 3475);
FORCEADD TAP..1
R 2
(-2750 3525);
FORCEPROP 3 LASTPIN (-2700 3525) SIG_NAME M_E_CPU1_SB_CA<5>
J 0
(-2690 3535);
DISPLAY 0.659574 (-2690 3535);
PAINT MONO (-2690 3535);
DISPLAY INVISIBLE (-2690 3535);
FORCEPROP 1 LASTPIN (-2700 3525) BN 5
J 2
(-2688 3533);
DISPLAY 0.680851 (-2688 3533);
PAINT GREEN (-2688 3533);
FORCEPROP 2 LAST CDS_LIB standard
J 0
(-2750 3525);
DISPLAY INVISIBLE (-2750 3525);
FORCEPROP 1 LAST BODY_TYPE PLUMBING
J 2
(-2750 3575);
DISPLAY 0.872340 (-2750 3575);
PAINT GREEN (-2750 3575);
DISPLAY INVISIBLE (-2750 3575);
FORCEPROP 1 LAST HDL_TAP TRUE
J 2
(-3075 3400);
DISPLAY 0.872340 (-3075 3400);
DISPLAY INVISIBLE (-3075 3400);
FORCEPROP 1 LAST PATH I72
J 2
(-2748 3525);
DISPLAY 0.872340 (-2748 3525);
PAINT GREEN (-2748 3525);
DISPLAY INVISIBLE (-2748 3525);
FORCEADD TAP..1
R 2
(-2750 3575);
FORCEPROP 3 LASTPIN (-2700 3575) SIG_NAME M_E_CPU1_SB_CA<6>
J 0
(-2690 3585);
DISPLAY 0.659574 (-2690 3585);
PAINT MONO (-2690 3585);
DISPLAY INVISIBLE (-2690 3585);
FORCEPROP 1 LASTPIN (-2700 3575) BN 6
J 2
(-2688 3583);
DISPLAY 0.680851 (-2688 3583);
PAINT GREEN (-2688 3583);
FORCEPROP 2 LAST CDS_LIB standard
J 0
(-2750 3575);
DISPLAY INVISIBLE (-2750 3575);
FORCEPROP 1 LAST BODY_TYPE PLUMBING
J 2
(-2750 3625);
DISPLAY 0.872340 (-2750 3625);
PAINT GREEN (-2750 3625);
DISPLAY INVISIBLE (-2750 3625);
FORCEPROP 1 LAST HDL_TAP TRUE
J 2
(-3075 3450);
DISPLAY 0.872340 (-3075 3450);
DISPLAY INVISIBLE (-3075 3450);
FORCEPROP 1 LAST PATH I73
J 2
(-2748 3575);
DISPLAY 0.872340 (-2748 3575);
PAINT GREEN (-2748 3575);
DISPLAY INVISIBLE (-2748 3575);
FORCEADD TAP..1
R 2
(-2750 3725);
FORCEPROP 3 LASTPIN (-2700 3725) SIG_NAME M_E_CPU1_SA_CA<1>
J 0
(-2690 3735);
DISPLAY 0.659574 (-2690 3735);
PAINT MONO (-2690 3735);
DISPLAY INVISIBLE (-2690 3735);
FORCEPROP 1 LASTPIN (-2700 3725) BN 1
J 2
(-2688 3733);
DISPLAY 0.680851 (-2688 3733);
PAINT GREEN (-2688 3733);
FORCEPROP 2 LAST CDS_LIB standard
J 0
(-2750 3725);
DISPLAY INVISIBLE (-2750 3725);
FORCEPROP 1 LAST BODY_TYPE PLUMBING
J 2
(-2750 3775);
DISPLAY 0.872340 (-2750 3775);
PAINT GREEN (-2750 3775);
DISPLAY INVISIBLE (-2750 3775);
FORCEPROP 1 LAST HDL_TAP TRUE
J 2
(-3075 3600);
DISPLAY 0.872340 (-3075 3600);
DISPLAY INVISIBLE (-3075 3600);
FORCEPROP 1 LAST PATH I74
J 2
(-2748 3725);
DISPLAY 0.872340 (-2748 3725);
PAINT GREEN (-2748 3725);
DISPLAY INVISIBLE (-2748 3725);
FORCEADD TAP..1
R 2
(-2750 3675);
FORCEPROP 3 LASTPIN (-2700 3675) SIG_NAME M_E_CPU1_SA_CA<0>
J 0
(-2690 3685);
DISPLAY 0.659574 (-2690 3685);
PAINT MONO (-2690 3685);
DISPLAY INVISIBLE (-2690 3685);
FORCEPROP 1 LASTPIN (-2700 3675) BN 0
J 2
(-2688 3683);
DISPLAY 0.680851 (-2688 3683);
PAINT GREEN (-2688 3683);
FORCEPROP 2 LAST CDS_LIB standard
J 0
(-2750 3675);
DISPLAY INVISIBLE (-2750 3675);
FORCEPROP 1 LAST BODY_TYPE PLUMBING
J 2
(-2750 3725);
DISPLAY 0.872340 (-2750 3725);
PAINT GREEN (-2750 3725);
DISPLAY INVISIBLE (-2750 3725);
FORCEPROP 1 LAST HDL_TAP TRUE
J 2
(-3075 3550);
DISPLAY 0.872340 (-3075 3550);
DISPLAY INVISIBLE (-3075 3550);
FORCEPROP 1 LAST PATH I75
J 2
(-2748 3675);
DISPLAY 0.872340 (-2748 3675);
PAINT GREEN (-2748 3675);
DISPLAY INVISIBLE (-2748 3675);
FORCEADD TAP..1
R 2
(-2750 3775);
FORCEPROP 3 LASTPIN (-2700 3775) SIG_NAME M_E_CPU1_SA_CA<2>
J 0
(-2690 3785);
DISPLAY 0.659574 (-2690 3785);
PAINT MONO (-2690 3785);
DISPLAY INVISIBLE (-2690 3785);
FORCEPROP 1 LASTPIN (-2700 3775) BN 2
J 2
(-2688 3783);
DISPLAY 0.680851 (-2688 3783);
PAINT GREEN (-2688 3783);
FORCEPROP 2 LAST CDS_LIB standard
J 0
(-2750 3775);
DISPLAY INVISIBLE (-2750 3775);
FORCEPROP 1 LAST BODY_TYPE PLUMBING
J 2
(-2750 3825);
DISPLAY 0.872340 (-2750 3825);
PAINT GREEN (-2750 3825);
DISPLAY INVISIBLE (-2750 3825);
FORCEPROP 1 LAST HDL_TAP TRUE
J 2
(-3075 3650);
DISPLAY 0.872340 (-3075 3650);
DISPLAY INVISIBLE (-3075 3650);
FORCEPROP 1 LAST PATH I76
J 2
(-2748 3775);
DISPLAY 0.872340 (-2748 3775);
PAINT GREEN (-2748 3775);
DISPLAY INVISIBLE (-2748 3775);
FORCEADD TAP..1
R 2
(-2750 3825);
FORCEPROP 3 LASTPIN (-2700 3825) SIG_NAME M_E_CPU1_SA_CA<3>
J 0
(-2690 3835);
DISPLAY 0.659574 (-2690 3835);
PAINT MONO (-2690 3835);
DISPLAY INVISIBLE (-2690 3835);
FORCEPROP 1 LASTPIN (-2700 3825) BN 3
J 2
(-2688 3833);
DISPLAY 0.680851 (-2688 3833);
PAINT GREEN (-2688 3833);
FORCEPROP 2 LAST CDS_LIB standard
J 0
(-2750 3825);
DISPLAY INVISIBLE (-2750 3825);
FORCEPROP 1 LAST BODY_TYPE PLUMBING
J 2
(-2750 3875);
DISPLAY 0.872340 (-2750 3875);
PAINT GREEN (-2750 3875);
DISPLAY INVISIBLE (-2750 3875);
FORCEPROP 1 LAST HDL_TAP TRUE
J 2
(-3075 3700);
DISPLAY 0.872340 (-3075 3700);
DISPLAY INVISIBLE (-3075 3700);
FORCEPROP 1 LAST PATH I77
J 2
(-2748 3825);
DISPLAY 0.872340 (-2748 3825);
PAINT GREEN (-2748 3825);
DISPLAY INVISIBLE (-2748 3825);
FORCEADD TAP..1
R 2
(-2750 3875);
FORCEPROP 3 LASTPIN (-2700 3875) SIG_NAME M_E_CPU1_SA_CA<4>
J 0
(-2690 3885);
DISPLAY 0.659574 (-2690 3885);
PAINT MONO (-2690 3885);
DISPLAY INVISIBLE (-2690 3885);
FORCEPROP 1 LASTPIN (-2700 3875) BN 4
J 2
(-2688 3883);
DISPLAY 0.680851 (-2688 3883);
PAINT GREEN (-2688 3883);
FORCEPROP 2 LAST CDS_LIB standard
J 0
(-2750 3875);
DISPLAY INVISIBLE (-2750 3875);
FORCEPROP 1 LAST BODY_TYPE PLUMBING
J 2
(-2750 3925);
DISPLAY 0.872340 (-2750 3925);
PAINT GREEN (-2750 3925);
DISPLAY INVISIBLE (-2750 3925);
FORCEPROP 1 LAST HDL_TAP TRUE
J 2
(-3075 3750);
DISPLAY 0.872340 (-3075 3750);
DISPLAY INVISIBLE (-3075 3750);
FORCEPROP 1 LAST PATH I78
J 2
(-2748 3875);
DISPLAY 0.872340 (-2748 3875);
PAINT GREEN (-2748 3875);
DISPLAY INVISIBLE (-2748 3875);
FORCEADD TAP..1
R 2
(-2750 3925);
FORCEPROP 3 LASTPIN (-2700 3925) SIG_NAME M_E_CPU1_SA_CA<5>
J 0
(-2690 3935);
DISPLAY 0.659574 (-2690 3935);
PAINT MONO (-2690 3935);
DISPLAY INVISIBLE (-2690 3935);
FORCEPROP 1 LASTPIN (-2700 3925) BN 5
J 2
(-2688 3933);
DISPLAY 0.680851 (-2688 3933);
PAINT GREEN (-2688 3933);
FORCEPROP 2 LAST CDS_LIB standard
J 0
(-2750 3925);
DISPLAY INVISIBLE (-2750 3925);
FORCEPROP 1 LAST BODY_TYPE PLUMBING
J 2
(-2750 3975);
DISPLAY 0.872340 (-2750 3975);
PAINT GREEN (-2750 3975);
DISPLAY INVISIBLE (-2750 3975);
FORCEPROP 1 LAST HDL_TAP TRUE
J 2
(-3075 3800);
DISPLAY 0.872340 (-3075 3800);
DISPLAY INVISIBLE (-3075 3800);
FORCEPROP 1 LAST PATH I79
J 2
(-2748 3925);
DISPLAY 0.872340 (-2748 3925);
PAINT GREEN (-2748 3925);
DISPLAY INVISIBLE (-2748 3925);
FORCEADD TAP..1
R 2
(-2750 3975);
FORCEPROP 3 LASTPIN (-2700 3975) SIG_NAME M_E_CPU1_SA_CA<6>
J 0
(-2690 3985);
DISPLAY 0.659574 (-2690 3985);
PAINT MONO (-2690 3985);
DISPLAY INVISIBLE (-2690 3985);
FORCEPROP 1 LASTPIN (-2700 3975) BN 6
J 2
(-2688 3983);
DISPLAY 0.680851 (-2688 3983);
PAINT GREEN (-2688 3983);
FORCEPROP 2 LAST CDS_LIB standard
J 0
(-2750 3975);
DISPLAY INVISIBLE (-2750 3975);
FORCEPROP 1 LAST BODY_TYPE PLUMBING
J 2
(-2750 4025);
DISPLAY 0.872340 (-2750 4025);
PAINT GREEN (-2750 4025);
DISPLAY INVISIBLE (-2750 4025);
FORCEPROP 1 LAST HDL_TAP TRUE
J 2
(-3075 3850);
DISPLAY 0.872340 (-3075 3850);
DISPLAY INVISIBLE (-3075 3850);
FORCEPROP 1 LAST PATH I80
J 2
(-2748 3975);
DISPLAY 0.872340 (-2748 3975);
PAINT GREEN (-2748 3975);
DISPLAY INVISIBLE (-2748 3975);
FORCEADD TAP..1
(-1100 2125);
FORCEPROP 3 LASTPIN (-1150 2125) SIG_NAME M_E_CPU1_SB_DQ<27>
J 0
(-1140 2135);
DISPLAY 0.659574 (-1140 2135);
PAINT MONO (-1140 2135);
DISPLAY INVISIBLE (-1140 2135);
FORCEPROP 1 LASTPIN (-1150 2125) BN 27
J 0
(-1162 2133);
DISPLAY 0.680851 (-1162 2133);
PAINT GREEN (-1162 2133);
FORCEPROP 2 LAST CDS_LIB standard
J 0
(-1100 2125);
DISPLAY INVISIBLE (-1100 2125);
FORCEPROP 1 LAST BODY_TYPE PLUMBING
J 0
(-1100 2175);
DISPLAY 0.872340 (-1100 2175);
PAINT GREEN (-1100 2175);
DISPLAY INVISIBLE (-1100 2175);
FORCEPROP 1 LAST HDL_TAP TRUE
J 0
(-775 2000);
DISPLAY 0.872340 (-775 2000);
DISPLAY INVISIBLE (-775 2000);
FORCEPROP 1 LAST PATH I81
J 0
(-1102 2125);
DISPLAY 0.872340 (-1102 2125);
PAINT GREEN (-1102 2125);
DISPLAY INVISIBLE (-1102 2125);
FORCEADD TAP..1
(-1100 2075);
FORCEPROP 3 LASTPIN (-1150 2075) SIG_NAME M_E_CPU1_SB_DQ<26>
J 0
(-1140 2085);
DISPLAY 0.659574 (-1140 2085);
PAINT MONO (-1140 2085);
DISPLAY INVISIBLE (-1140 2085);
FORCEPROP 1 LASTPIN (-1150 2075) BN 26
J 0
(-1162 2083);
DISPLAY 0.680851 (-1162 2083);
PAINT GREEN (-1162 2083);
FORCEPROP 2 LAST CDS_LIB standard
J 0
(-1100 2075);
DISPLAY INVISIBLE (-1100 2075);
FORCEPROP 1 LAST BODY_TYPE PLUMBING
J 0
(-1100 2125);
DISPLAY 0.872340 (-1100 2125);
PAINT GREEN (-1100 2125);
DISPLAY INVISIBLE (-1100 2125);
FORCEPROP 1 LAST HDL_TAP TRUE
J 0
(-775 1950);
DISPLAY 0.872340 (-775 1950);
DISPLAY INVISIBLE (-775 1950);
FORCEPROP 1 LAST PATH I82
J 0
(-1102 2075);
DISPLAY 0.872340 (-1102 2075);
PAINT GREEN (-1102 2075);
DISPLAY INVISIBLE (-1102 2075);
FORCEADD TAP..1
(-1100 2025);
FORCEPROP 3 LASTPIN (-1150 2025) SIG_NAME M_E_CPU1_SB_DQ<25>
J 0
(-1140 2035);
DISPLAY 0.659574 (-1140 2035);
PAINT MONO (-1140 2035);
DISPLAY INVISIBLE (-1140 2035);
FORCEPROP 1 LASTPIN (-1150 2025) BN 25
J 0
(-1162 2033);
DISPLAY 0.680851 (-1162 2033);
PAINT GREEN (-1162 2033);
FORCEPROP 2 LAST CDS_LIB standard
J 0
(-1100 2025);
DISPLAY INVISIBLE (-1100 2025);
FORCEPROP 1 LAST BODY_TYPE PLUMBING
J 0
(-1100 2075);
DISPLAY 0.872340 (-1100 2075);
PAINT GREEN (-1100 2075);
DISPLAY INVISIBLE (-1100 2075);
FORCEPROP 1 LAST HDL_TAP TRUE
J 0
(-775 1900);
DISPLAY 0.872340 (-775 1900);
DISPLAY INVISIBLE (-775 1900);
FORCEPROP 1 LAST PATH I83
J 0
(-1102 2025);
DISPLAY 0.872340 (-1102 2025);
PAINT GREEN (-1102 2025);
DISPLAY INVISIBLE (-1102 2025);
FORCEADD TAP..1
(-1100 2225);
FORCEPROP 3 LASTPIN (-1150 2225) SIG_NAME M_E_CPU1_SB_DQ<29>
J 0
(-1140 2235);
DISPLAY 0.659574 (-1140 2235);
PAINT MONO (-1140 2235);
DISPLAY INVISIBLE (-1140 2235);
FORCEPROP 1 LASTPIN (-1150 2225) BN 29
J 0
(-1162 2233);
DISPLAY 0.680851 (-1162 2233);
PAINT GREEN (-1162 2233);
FORCEPROP 2 LAST CDS_LIB standard
J 0
(-1100 2225);
DISPLAY INVISIBLE (-1100 2225);
FORCEPROP 1 LAST BODY_TYPE PLUMBING
J 0
(-1100 2275);
DISPLAY 0.872340 (-1100 2275);
PAINT GREEN (-1100 2275);
DISPLAY INVISIBLE (-1100 2275);
FORCEPROP 1 LAST HDL_TAP TRUE
J 0
(-775 2100);
DISPLAY 0.872340 (-775 2100);
DISPLAY INVISIBLE (-775 2100);
FORCEPROP 1 LAST PATH I84
J 0
(-1102 2225);
DISPLAY 0.872340 (-1102 2225);
PAINT GREEN (-1102 2225);
DISPLAY INVISIBLE (-1102 2225);
FORCEADD TAP..1
(-1100 2175);
FORCEPROP 3 LASTPIN (-1150 2175) SIG_NAME M_E_CPU1_SB_DQ<28>
J 0
(-1140 2185);
DISPLAY 0.659574 (-1140 2185);
PAINT MONO (-1140 2185);
DISPLAY INVISIBLE (-1140 2185);
FORCEPROP 1 LASTPIN (-1150 2175) BN 28
J 0
(-1162 2183);
DISPLAY 0.680851 (-1162 2183);
PAINT GREEN (-1162 2183);
FORCEPROP 2 LAST CDS_LIB standard
J 0
(-1100 2175);
DISPLAY INVISIBLE (-1100 2175);
FORCEPROP 1 LAST BODY_TYPE PLUMBING
J 0
(-1100 2225);
DISPLAY 0.872340 (-1100 2225);
PAINT GREEN (-1100 2225);
DISPLAY INVISIBLE (-1100 2225);
FORCEPROP 1 LAST HDL_TAP TRUE
J 0
(-775 2050);
DISPLAY 0.872340 (-775 2050);
DISPLAY INVISIBLE (-775 2050);
FORCEPROP 1 LAST PATH I85
J 0
(-1102 2175);
DISPLAY 0.872340 (-1102 2175);
PAINT GREEN (-1102 2175);
DISPLAY INVISIBLE (-1102 2175);
FORCEADD TAP..1
(-1100 2325);
FORCEPROP 3 LASTPIN (-1150 2325) SIG_NAME M_E_CPU1_SB_DQ<31>
J 0
(-1140 2335);
DISPLAY 0.659574 (-1140 2335);
PAINT MONO (-1140 2335);
DISPLAY INVISIBLE (-1140 2335);
FORCEPROP 1 LASTPIN (-1150 2325) BN 31
J 0
(-1162 2333);
DISPLAY 0.680851 (-1162 2333);
PAINT GREEN (-1162 2333);
FORCEPROP 2 LAST CDS_LIB standard
J 0
(-1100 2325);
DISPLAY INVISIBLE (-1100 2325);
FORCEPROP 1 LAST BODY_TYPE PLUMBING
J 0
(-1100 2375);
DISPLAY 0.872340 (-1100 2375);
PAINT GREEN (-1100 2375);
DISPLAY INVISIBLE (-1100 2375);
FORCEPROP 1 LAST HDL_TAP TRUE
J 0
(-775 2200);
DISPLAY 0.872340 (-775 2200);
DISPLAY INVISIBLE (-775 2200);
FORCEPROP 1 LAST PATH I86
J 0
(-1102 2325);
DISPLAY 0.872340 (-1102 2325);
PAINT GREEN (-1102 2325);
DISPLAY INVISIBLE (-1102 2325);
FORCEADD TAP..1
(-1100 2275);
FORCEPROP 3 LASTPIN (-1150 2275) SIG_NAME M_E_CPU1_SB_DQ<30>
J 0
(-1140 2285);
DISPLAY 0.659574 (-1140 2285);
PAINT MONO (-1140 2285);
DISPLAY INVISIBLE (-1140 2285);
FORCEPROP 1 LASTPIN (-1150 2275) BN 30
J 0
(-1162 2283);
DISPLAY 0.680851 (-1162 2283);
PAINT GREEN (-1162 2283);
FORCEPROP 2 LAST CDS_LIB standard
J 0
(-1100 2275);
DISPLAY INVISIBLE (-1100 2275);
FORCEPROP 1 LAST BODY_TYPE PLUMBING
J 0
(-1100 2325);
DISPLAY 0.872340 (-1100 2325);
PAINT GREEN (-1100 2325);
DISPLAY INVISIBLE (-1100 2325);
FORCEPROP 1 LAST HDL_TAP TRUE
J 0
(-775 2150);
DISPLAY 0.872340 (-775 2150);
DISPLAY INVISIBLE (-775 2150);
FORCEPROP 1 LAST PATH I87
J 0
(-1102 2275);
DISPLAY 0.872340 (-1102 2275);
PAINT GREEN (-1102 2275);
DISPLAY INVISIBLE (-1102 2275);
FORCEADD TAP..1
(-1100 2425);
FORCEPROP 3 LASTPIN (-1150 2425) SIG_NAME M_E_CPU1_SA_DQ<0>
J 0
(-1140 2435);
DISPLAY 0.659574 (-1140 2435);
PAINT MONO (-1140 2435);
DISPLAY INVISIBLE (-1140 2435);
FORCEPROP 1 LASTPIN (-1150 2425) BN 0
J 0
(-1162 2433);
DISPLAY 0.680851 (-1162 2433);
PAINT GREEN (-1162 2433);
FORCEPROP 2 LAST CDS_LIB standard
J 0
(-1100 2425);
PAINT MONO (-1100 2425);
DISPLAY INVISIBLE (-1100 2425);
FORCEPROP 1 LAST BODY_TYPE PLUMBING
J 0
(-1100 2475);
DISPLAY 0.872340 (-1100 2475);
PAINT GREEN (-1100 2475);
DISPLAY INVISIBLE (-1100 2475);
FORCEPROP 1 LAST HDL_TAP TRUE
J 0
(-775 2300);
DISPLAY 0.872340 (-775 2300);
DISPLAY INVISIBLE (-775 2300);
FORCEPROP 1 LAST PATH I88
J 0
(-1102 2425);
DISPLAY 0.872340 (-1102 2425);
PAINT GREEN (-1102 2425);
DISPLAY INVISIBLE (-1102 2425);
FORCEADD TAP..1
(-1100 2475);
FORCEPROP 3 LASTPIN (-1150 2475) SIG_NAME M_E_CPU1_SA_DQ<1>
J 0
(-1140 2485);
DISPLAY 0.659574 (-1140 2485);
PAINT MONO (-1140 2485);
DISPLAY INVISIBLE (-1140 2485);
FORCEPROP 1 LASTPIN (-1150 2475) BN 1
J 0
(-1162 2483);
DISPLAY 0.680851 (-1162 2483);
PAINT GREEN (-1162 2483);
FORCEPROP 2 LAST CDS_LIB standard
J 0
(-1100 2475);
PAINT MONO (-1100 2475);
DISPLAY INVISIBLE (-1100 2475);
FORCEPROP 1 LAST BODY_TYPE PLUMBING
J 0
(-1100 2525);
DISPLAY 0.872340 (-1100 2525);
PAINT GREEN (-1100 2525);
DISPLAY INVISIBLE (-1100 2525);
FORCEPROP 1 LAST HDL_TAP TRUE
J 0
(-775 2350);
DISPLAY 0.872340 (-775 2350);
DISPLAY INVISIBLE (-775 2350);
FORCEPROP 1 LAST PATH I89
J 0
(-1102 2475);
DISPLAY 0.872340 (-1102 2475);
PAINT GREEN (-1102 2475);
DISPLAY INVISIBLE (-1102 2475);
FORCEADD OFFPAGE..1
(-3600 1475);
FORCEPROP 2 LAST $XR0 106 
J 0
(-3882 1475);
DISPLAY 0.638298 (-3882 1475);
PAINT MONO (-3882 1475);
FORCEPROP 2 LAST CDS_LIB standard
J 0
(-3600 1475);
PAINT MONO (-3600 1475);
DISPLAY INVISIBLE (-3600 1475);
FORCEPROP 1 LAST OFFPAGE TRUE
J 0
(-3275 1350);
DISPLAY 0.872340 (-3275 1350);
DISPLAY INVISIBLE (-3275 1350);
FORCEPROP 1 LAST COMMENT_BODY TRUE
J 0
(-3475 1375);
DISPLAY 0.872340 (-3475 1375);
PAINT GREEN (-3475 1375);
DISPLAY INVISIBLE (-3475 1375);
FORCEPROP 2 LAST PATH I9
J 0
(-3550 1550);
DISPLAY 1.021277 (-3550 1550);
DISPLAY INVISIBLE (-3550 1550);
FORCEADD TAP..1
(-1100 2625);
FORCEPROP 3 LASTPIN (-1150 2625) SIG_NAME M_E_CPU1_SA_DQ<4>
J 0
(-1140 2635);
DISPLAY 0.659574 (-1140 2635);
PAINT MONO (-1140 2635);
DISPLAY INVISIBLE (-1140 2635);
FORCEPROP 1 LASTPIN (-1150 2625) BN 4
J 0
(-1162 2633);
DISPLAY 0.680851 (-1162 2633);
PAINT GREEN (-1162 2633);
FORCEPROP 2 LAST CDS_LIB standard
J 0
(-1100 2625);
PAINT MONO (-1100 2625);
DISPLAY INVISIBLE (-1100 2625);
FORCEPROP 1 LAST BODY_TYPE PLUMBING
J 0
(-1100 2675);
DISPLAY 0.872340 (-1100 2675);
PAINT GREEN (-1100 2675);
DISPLAY INVISIBLE (-1100 2675);
FORCEPROP 1 LAST HDL_TAP TRUE
J 0
(-775 2500);
DISPLAY 0.872340 (-775 2500);
DISPLAY INVISIBLE (-775 2500);
FORCEPROP 1 LAST PATH I90
J 0
(-1102 2625);
DISPLAY 0.872340 (-1102 2625);
PAINT GREEN (-1102 2625);
DISPLAY INVISIBLE (-1102 2625);
FORCEADD TAP..1
(-1100 2575);
FORCEPROP 3 LASTPIN (-1150 2575) SIG_NAME M_E_CPU1_SA_DQ<3>
J 0
(-1140 2585);
DISPLAY 0.659574 (-1140 2585);
PAINT MONO (-1140 2585);
DISPLAY INVISIBLE (-1140 2585);
FORCEPROP 1 LASTPIN (-1150 2575) BN 3
J 0
(-1162 2583);
DISPLAY 0.680851 (-1162 2583);
PAINT GREEN (-1162 2583);
FORCEPROP 2 LAST CDS_LIB standard
J 0
(-1100 2575);
PAINT MONO (-1100 2575);
DISPLAY INVISIBLE (-1100 2575);
FORCEPROP 1 LAST BODY_TYPE PLUMBING
J 0
(-1100 2625);
DISPLAY 0.872340 (-1100 2625);
PAINT GREEN (-1100 2625);
DISPLAY INVISIBLE (-1100 2625);
FORCEPROP 1 LAST HDL_TAP TRUE
J 0
(-775 2450);
DISPLAY 0.872340 (-775 2450);
DISPLAY INVISIBLE (-775 2450);
FORCEPROP 1 LAST PATH I91
J 0
(-1102 2575);
DISPLAY 0.872340 (-1102 2575);
PAINT GREEN (-1102 2575);
DISPLAY INVISIBLE (-1102 2575);
FORCEADD TAP..1
(-1100 2525);
FORCEPROP 3 LASTPIN (-1150 2525) SIG_NAME M_E_CPU1_SA_DQ<2>
J 0
(-1140 2535);
DISPLAY 0.659574 (-1140 2535);
PAINT MONO (-1140 2535);
DISPLAY INVISIBLE (-1140 2535);
FORCEPROP 1 LASTPIN (-1150 2525) BN 2
J 0
(-1162 2533);
DISPLAY 0.680851 (-1162 2533);
PAINT GREEN (-1162 2533);
FORCEPROP 2 LAST CDS_LIB standard
J 0
(-1100 2525);
PAINT MONO (-1100 2525);
DISPLAY INVISIBLE (-1100 2525);
FORCEPROP 1 LAST BODY_TYPE PLUMBING
J 0
(-1100 2575);
DISPLAY 0.872340 (-1100 2575);
PAINT GREEN (-1100 2575);
DISPLAY INVISIBLE (-1100 2575);
FORCEPROP 1 LAST HDL_TAP TRUE
J 0
(-775 2400);
DISPLAY 0.872340 (-775 2400);
DISPLAY INVISIBLE (-775 2400);
FORCEPROP 1 LAST PATH I92
J 0
(-1102 2525);
DISPLAY 0.872340 (-1102 2525);
PAINT GREEN (-1102 2525);
DISPLAY INVISIBLE (-1102 2525);
FORCEADD TAP..1
(-1100 2725);
FORCEPROP 3 LASTPIN (-1150 2725) SIG_NAME M_E_CPU1_SA_DQ<6>
J 0
(-1140 2735);
DISPLAY 0.659574 (-1140 2735);
PAINT MONO (-1140 2735);
DISPLAY INVISIBLE (-1140 2735);
FORCEPROP 1 LASTPIN (-1150 2725) BN 6
J 0
(-1162 2733);
DISPLAY 0.680851 (-1162 2733);
PAINT GREEN (-1162 2733);
FORCEPROP 2 LAST CDS_LIB standard
J 0
(-1100 2725);
PAINT MONO (-1100 2725);
DISPLAY INVISIBLE (-1100 2725);
FORCEPROP 1 LAST BODY_TYPE PLUMBING
J 0
(-1100 2775);
DISPLAY 0.872340 (-1100 2775);
PAINT GREEN (-1100 2775);
DISPLAY INVISIBLE (-1100 2775);
FORCEPROP 1 LAST HDL_TAP TRUE
J 0
(-775 2600);
DISPLAY 0.872340 (-775 2600);
DISPLAY INVISIBLE (-775 2600);
FORCEPROP 1 LAST PATH I93
J 0
(-1102 2725);
DISPLAY 0.872340 (-1102 2725);
PAINT GREEN (-1102 2725);
DISPLAY INVISIBLE (-1102 2725);
FORCEADD TAP..1
(-1100 2675);
FORCEPROP 3 LASTPIN (-1150 2675) SIG_NAME M_E_CPU1_SA_DQ<5>
J 0
(-1140 2685);
DISPLAY 0.659574 (-1140 2685);
PAINT MONO (-1140 2685);
DISPLAY INVISIBLE (-1140 2685);
FORCEPROP 1 LASTPIN (-1150 2675) BN 5
J 0
(-1162 2683);
DISPLAY 0.680851 (-1162 2683);
PAINT GREEN (-1162 2683);
FORCEPROP 2 LAST CDS_LIB standard
J 0
(-1100 2675);
PAINT MONO (-1100 2675);
DISPLAY INVISIBLE (-1100 2675);
FORCEPROP 1 LAST BODY_TYPE PLUMBING
J 0
(-1100 2725);
DISPLAY 0.872340 (-1100 2725);
PAINT GREEN (-1100 2725);
DISPLAY INVISIBLE (-1100 2725);
FORCEPROP 1 LAST HDL_TAP TRUE
J 0
(-775 2550);
DISPLAY 0.872340 (-775 2550);
DISPLAY INVISIBLE (-775 2550);
FORCEPROP 1 LAST PATH I94
J 0
(-1102 2675);
DISPLAY 0.872340 (-1102 2675);
PAINT GREEN (-1102 2675);
DISPLAY INVISIBLE (-1102 2675);
FORCEADD TAP..1
(-1100 2875);
FORCEPROP 3 LASTPIN (-1150 2875) SIG_NAME M_E_CPU1_SA_DQ<9>
J 0
(-1140 2885);
DISPLAY 0.659574 (-1140 2885);
PAINT MONO (-1140 2885);
DISPLAY INVISIBLE (-1140 2885);
FORCEPROP 1 LASTPIN (-1150 2875) BN 9
J 0
(-1162 2883);
DISPLAY 0.680851 (-1162 2883);
PAINT GREEN (-1162 2883);
FORCEPROP 2 LAST CDS_LIB standard
J 0
(-1100 2875);
PAINT MONO (-1100 2875);
DISPLAY INVISIBLE (-1100 2875);
FORCEPROP 1 LAST BODY_TYPE PLUMBING
J 0
(-1100 2925);
DISPLAY 0.872340 (-1100 2925);
PAINT GREEN (-1100 2925);
DISPLAY INVISIBLE (-1100 2925);
FORCEPROP 1 LAST HDL_TAP TRUE
J 0
(-775 2750);
DISPLAY 0.872340 (-775 2750);
DISPLAY INVISIBLE (-775 2750);
FORCEPROP 1 LAST PATH I95
J 0
(-1102 2875);
DISPLAY 0.872340 (-1102 2875);
PAINT GREEN (-1102 2875);
DISPLAY INVISIBLE (-1102 2875);
FORCEADD TAP..1
(-1100 2775);
FORCEPROP 3 LASTPIN (-1150 2775) SIG_NAME M_E_CPU1_SA_DQ<7>
J 0
(-1140 2785);
DISPLAY 0.659574 (-1140 2785);
PAINT MONO (-1140 2785);
DISPLAY INVISIBLE (-1140 2785);
FORCEPROP 1 LASTPIN (-1150 2775) BN 7
J 0
(-1162 2783);
DISPLAY 0.680851 (-1162 2783);
PAINT GREEN (-1162 2783);
FORCEPROP 2 LAST CDS_LIB standard
J 0
(-1100 2775);
PAINT MONO (-1100 2775);
DISPLAY INVISIBLE (-1100 2775);
FORCEPROP 1 LAST BODY_TYPE PLUMBING
J 0
(-1100 2825);
DISPLAY 0.872340 (-1100 2825);
PAINT GREEN (-1100 2825);
DISPLAY INVISIBLE (-1100 2825);
FORCEPROP 1 LAST HDL_TAP TRUE
J 0
(-775 2650);
DISPLAY 0.872340 (-775 2650);
DISPLAY INVISIBLE (-775 2650);
FORCEPROP 1 LAST PATH I96
J 0
(-1102 2775);
DISPLAY 0.872340 (-1102 2775);
PAINT GREEN (-1102 2775);
DISPLAY INVISIBLE (-1102 2775);
FORCEADD TAP..1
(-1100 2825);
FORCEPROP 3 LASTPIN (-1150 2825) SIG_NAME M_E_CPU1_SA_DQ<8>
J 0
(-1140 2835);
DISPLAY 0.659574 (-1140 2835);
PAINT MONO (-1140 2835);
DISPLAY INVISIBLE (-1140 2835);
FORCEPROP 1 LASTPIN (-1150 2825) BN 8
J 0
(-1162 2833);
DISPLAY 0.680851 (-1162 2833);
PAINT GREEN (-1162 2833);
FORCEPROP 2 LAST CDS_LIB standard
J 0
(-1100 2825);
PAINT MONO (-1100 2825);
DISPLAY INVISIBLE (-1100 2825);
FORCEPROP 1 LAST BODY_TYPE PLUMBING
J 0
(-1100 2875);
DISPLAY 0.872340 (-1100 2875);
PAINT GREEN (-1100 2875);
DISPLAY INVISIBLE (-1100 2875);
FORCEPROP 1 LAST HDL_TAP TRUE
J 0
(-775 2700);
DISPLAY 0.872340 (-775 2700);
DISPLAY INVISIBLE (-775 2700);
FORCEPROP 1 LAST PATH I97
J 0
(-1102 2825);
DISPLAY 0.872340 (-1102 2825);
PAINT GREEN (-1102 2825);
DISPLAY INVISIBLE (-1102 2825);
FORCEADD TAP..1
(-1100 2925);
FORCEPROP 3 LASTPIN (-1150 2925) SIG_NAME M_E_CPU1_SA_DQ<10>
J 0
(-1140 2935);
DISPLAY 0.659574 (-1140 2935);
PAINT MONO (-1140 2935);
DISPLAY INVISIBLE (-1140 2935);
FORCEPROP 1 LASTPIN (-1150 2925) BN 10
J 0
(-1162 2933);
DISPLAY 0.680851 (-1162 2933);
PAINT GREEN (-1162 2933);
FORCEPROP 2 LAST CDS_LIB standard
J 0
(-1100 2925);
PAINT MONO (-1100 2925);
DISPLAY INVISIBLE (-1100 2925);
FORCEPROP 1 LAST BODY_TYPE PLUMBING
J 0
(-1100 2975);
DISPLAY 0.872340 (-1100 2975);
PAINT GREEN (-1100 2975);
DISPLAY INVISIBLE (-1100 2975);
FORCEPROP 1 LAST HDL_TAP TRUE
J 0
(-775 2800);
DISPLAY 0.872340 (-775 2800);
DISPLAY INVISIBLE (-775 2800);
FORCEPROP 1 LAST PATH I98
J 0
(-1102 2925);
DISPLAY 0.872340 (-1102 2925);
PAINT GREEN (-1102 2925);
DISPLAY INVISIBLE (-1102 2925);
FORCEADD TAP..1
(-1100 2975);
FORCEPROP 3 LASTPIN (-1150 2975) SIG_NAME M_E_CPU1_SA_DQ<11>
J 0
(-1140 2985);
DISPLAY 0.659574 (-1140 2985);
PAINT MONO (-1140 2985);
DISPLAY INVISIBLE (-1140 2985);
FORCEPROP 1 LASTPIN (-1150 2975) BN 11
J 0
(-1162 2983);
DISPLAY 0.680851 (-1162 2983);
PAINT GREEN (-1162 2983);
FORCEPROP 2 LAST CDS_LIB standard
J 0
(-1100 2975);
PAINT MONO (-1100 2975);
DISPLAY INVISIBLE (-1100 2975);
FORCEPROP 1 LAST BODY_TYPE PLUMBING
J 0
(-1100 3025);
DISPLAY 0.872340 (-1100 3025);
PAINT GREEN (-1100 3025);
DISPLAY INVISIBLE (-1100 3025);
FORCEPROP 1 LAST HDL_TAP TRUE
J 0
(-775 2850);
DISPLAY 0.872340 (-775 2850);
DISPLAY INVISIBLE (-775 2850);
FORCEPROP 1 LAST PATH I99
J 0
(-1102 2975);
DISPLAY 0.872340 (-1102 2975);
PAINT GREEN (-1102 2975);
DISPLAY INVISIBLE (-1102 2975);
FORCEADD CAD_NOTE..1
(750 -475);
FORCEPROP 0 LAST S1 PLACE THE BYPASS CAPS CLOSE TO DIMM
J 0
(625 -600);
DISPLAY 1.021277 (625 -600);
PAINT WHITE (625 -600);
FORCEPROP 2 LAST CDS_LIB logical_power
J 0
(750 -475);
PAINT MONO (750 -475);
DISPLAY INVISIBLE (750 -475);
FORCEPROP 1 LAST COMMENT_BODY TRUE
J 0
(775 -375);
DISPLAY 0.978723 (775 -375);
DISPLAY INVISIBLE (775 -375);
FORCEADD QUANTA_TITLE_BLOCK_C..1
(5225 -1775);
FORCEPROP 0 LAST CDS_CON_LAST_MODIFIED Fri Aug 25 14:01:26 2023
J 0
(3340 -1760);
PAINT MONO (3340 -1760);
DISPLAY INVISIBLE (3340 -1760);
FORCEPROP 2 LAST CUSTOM_TXT_CDS <XR_PAGE_TITLE>
J 0
(-2665 3475);
DISPLAY 0.638298 (-2665 3475);
PAINT PINK (-2665 3475);
DISPLAY INVISIBLE (-2665 3475);
FORCEPROP 2 LAST CUSTOM_TXT_CDS <NAME_1>
J 0
(2050 -1600);
FORCEPROP 2 LAST CUSTOM_TXT_CDS <NAME_2>
J 0
(2050 -1725);
FORCEPROP 2 LAST CUSTOM_TXT_CDS <Q_PROJ>
J 0
(2843 -1673);
DISPLAY 1.212766 (2843 -1673);
FORCEPROP 2 LAST CUSTOM_TXT_CDS <CON_LAST_MODIFIED>
J 0
(3340 -1760);
DISPLAY 0.978723 (3340 -1760);
FORCEPROP 2 LAST CUSTOM_TXT_CDS <Q_NUMBER>
J 0
(3822 -1672);
DISPLAY 1.212766 (3822 -1672);
FORCEPROP 2 LAST CUSTOM_TXT_CDS <CON_PAGE_NUM> OF <CON_TOTAL_PAGES>
J 0
(4779 -1757);
DISPLAY 0.978723 (4779 -1757);
FORCEPROP 2 LAST CUSTOM_TXT_CDS <Q_REV>
J 0
(5041 -1672);
DISPLAY 1.212766 (5041 -1672);
FORCEPROP 1 LAST Q_TITLE DDR5 - CPU1 CHE DIMM1(YELLOW)
J 0
(-4141 -1749);
DISPLAY 2.446809 (-4141 -1749);
PAINT GREEN (-4141 -1749);
FORCEPROP 1 LAST Q_DEPT 
J 1
(1462 -1726);
DISPLAY 1.957447 (1462 -1726);
PAINT GREEN (1462 -1726);
FORCEPROP 2 LAST CDS_XR_PAGE_TITLE CR-106 : @S9S_MB_2U_LIB.S9S_MB_2U(SCH_1):PAGE106
J 0
(-2665 3475);
DISPLAY 0.638298 (-2665 3475);
PAINT PINK (-2665 3475);
DISPLAY INVISIBLE (-2665 3475);
FORCEPROP 1 LAST COMMENT_BODY TRUE
J 0
(5237 -1788);
DISPLAY 0.978723 (5237 -1788);
PAINT GREEN (5237 -1788);
DISPLAY INVISIBLE (5237 -1788);
FORCEPROP 2 LAST PAGE_BORDER TRUE
J 0
(-2665 3475);
DISPLAY 0.638298 (-2665 3475);
PAINT PINK (-2665 3475);
DISPLAY INVISIBLE (-2665 3475);
FORCEPROP 1 LAST CDS_LMAN_SYM_OUTLINE -9475,6775,100,-125
J 0
(5225 -1775);
DISPLAY 0.468085 (5225 -1775);
PAINT GREEN (5225 -1775);
DISPLAY INVISIBLE (5225 -1775);
FORCEPROP 2 LAST CDS_LIB pure_quanta
J 0
(5225 -1775);
PAINT MONO (5225 -1775);
DISPLAY INVISIBLE (5225 -1775);
WIRE 17 -1 (-1050 4000)(-325 4000);
FORCEPROP 2 LAST SIG_NAME M_E_CPU1_SA_DQ<31:0>
J 0
(-985 4010);
DISPLAY 0.680851 (-985 4010);
PAINT WHITE (-985 4010);
WIRE 17 -1 (-3625 2600)(-2800 2600);
FORCEPROP 2 LAST SIG_NAME M_E_CPU1_SA_CB<7:0>
J 0
(-3535 2610);
DISPLAY 0.680851 (-3535 2610);
PAINT WHITE (-3535 2610);
WIRE 17 -1 (-2800 2450)(-2800 2500);
WIRE 17 -1 (-2800 2400)(-2800 2450);
WIRE 17 -1 (-2800 2500)(-2800 2550);
WIRE 17 -1 (-2800 2550)(-2800 2600);
WIRE 17 -1 (-2800 2350)(-2800 2400);
WIRE 17 -1 (-2800 2300)(-2800 2350);
WIRE 17 -1 (-2800 2250)(-2800 2300);
WIRE 17 -1 (-3625 2150)(-2800 2150);
FORCEPROP 2 LAST SIG_NAME M_E_CPU1_SB_CB<7:0>
J 0
(-3535 2160);
DISPLAY 0.680851 (-3535 2160);
PAINT WHITE (-3535 2160);
WIRE 17 -1 (-2800 3700)(-2800 3750);
WIRE 17 -1 (-2800 3750)(-2800 3800);
WIRE 17 -1 (-2800 3800)(-2800 3850);
WIRE 17 -1 (-2800 3850)(-2800 3900);
WIRE 17 -1 (-2800 3900)(-2800 3950);
WIRE 17 -1 (-2800 3950)(-2800 4000);
WIRE 17 -1 (-3625 4000)(-2800 4000);
FORCEPROP 2 LAST SIG_NAME M_E_CPU1_SA_CA<6:0>
J 0
(-3535 4010);
DISPLAY 0.680851 (-3535 4010);
PAINT WHITE (-3535 4010);
WIRE 17 -1 (-2800 3350)(-2800 3400);
WIRE 17 -1 (-2800 3300)(-2800 3350);
WIRE 17 -1 (-2800 3400)(-2800 3450);
WIRE 17 -1 (-2800 3450)(-2800 3500);
WIRE 17 -1 (-2800 3500)(-2800 3550);
WIRE 17 -1 (-2800 3550)(-2800 3600);
WIRE 17 -1 (-3625 3600)(-2800 3600);
FORCEPROP 2 LAST SIG_NAME M_E_CPU1_SB_CA<6:0>
J 0
(-3535 3610);
DISPLAY 0.680851 (-3535 3610);
PAINT WHITE (-3535 3610);
WIRE 17 -1 (-2800 2100)(-2800 2150);
WIRE 17 -1 (-2800 2050)(-2800 2100);
WIRE 17 -1 (-2800 2000)(-2800 2050);
WIRE 17 -1 (-2800 1950)(-2800 2000);
WIRE 17 -1 (-2800 1900)(-2800 1950);
WIRE 17 -1 (-2800 1850)(-2800 1900);
WIRE 17 -1 (-2800 1800)(-2800 1850);
WIRE 17 -1 (-1050 3950)(-1050 4000);
WIRE 17 -1 (-1050 3900)(-1050 3950);
WIRE 17 -1 (-1050 3850)(-1050 3900);
WIRE 17 -1 (-1050 3800)(-1050 3850);
WIRE 17 -1 (-1050 3750)(-1050 3800);
WIRE 17 -1 (-1050 3700)(-1050 3750);
WIRE 17 -1 (-1050 3650)(-1050 3700);
WIRE 17 -1 (-1050 3600)(-1050 3650);
WIRE 17 -1 (-1050 3550)(-1050 3600);
WIRE 17 -1 (-1050 3500)(-1050 3550);
WIRE 17 -1 (-1050 3450)(-1050 3500);
WIRE 17 -1 (-1050 3400)(-1050 3450);
WIRE 17 -1 (-1050 3350)(-1050 3400);
WIRE 17 -1 (-1050 3300)(-1050 3350);
WIRE 17 -1 (-1050 3250)(-1050 3300);
WIRE 17 -1 (-1050 3200)(-1050 3250);
WIRE 17 -1 (-1050 3150)(-1050 3200);
WIRE 17 -1 (-1050 3100)(-1050 3150);
WIRE 17 -1 (-1050 3050)(-1050 3100);
WIRE 17 -1 (-1050 3000)(-1050 3050);
WIRE 17 -1 (-1050 2950)(-1050 3000);
WIRE 17 -1 (-1050 2900)(-1050 2950);
WIRE 17 -1 (-1050 2850)(-1050 2900);
WIRE 17 -1 (-1050 2800)(-1050 2850);
WIRE 17 -1 (-1050 2750)(-1050 2800);
WIRE 17 -1 (-1050 2700)(-1050 2750);
WIRE 17 -1 (-1050 2650)(-1050 2700);
WIRE 17 -1 (-1050 2600)(-1050 2650);
WIRE 17 -1 (-1050 2550)(-1050 2600);
WIRE 17 -1 (-1050 2500)(-1050 2550);
WIRE 17 -1 (-1050 2450)(-1050 2500);
WIRE 17 -1 (-1050 2350)(-325 2350);
FORCEPROP 2 LAST SIG_NAME M_E_CPU1_SB_DQ<31:0>
J 0
(-985 2360);
DISPLAY 0.680851 (-985 2360);
PAINT WHITE (-985 2360);
WIRE 17 -1 (-1050 2200)(-1050 2250);
WIRE 17 -1 (-1050 2150)(-1050 2200);
WIRE 17 -1 (-1050 2250)(-1050 2300);
WIRE 17 -1 (-1050 2300)(-1050 2350);
WIRE 17 -1 (-1050 2100)(-1050 2150);
WIRE 17 -1 (-1050 2050)(-1050 2100);
WIRE 17 -1 (-1050 2000)(-1050 2050);
WIRE 17 -1 (-1050 1950)(-1050 2000);
WIRE 17 -1 (-1050 1900)(-1050 1950);
WIRE 17 -1 (-1050 1850)(-1050 1900);
WIRE 17 -1 (-1050 1800)(-1050 1850);
WIRE 17 -1 (-1050 1750)(-1050 1800);
WIRE 17 -1 (-1050 1700)(-1050 1750);
WIRE 17 -1 (-1050 1650)(-1050 1700);
WIRE 17 -1 (-1050 1600)(-1050 1650);
WIRE 17 -1 (-1050 1550)(-1050 1600);
WIRE 17 -1 (-1050 1500)(-1050 1550);
WIRE 17 -1 (-1050 1450)(-1050 1500);
WIRE 17 -1 (-1050 1400)(-1050 1450);
WIRE 17 -1 (-1050 1350)(-1050 1400);
WIRE 17 -1 (-1050 1300)(-1050 1350);
WIRE 17 -1 (-1050 1250)(-1050 1300);
WIRE 17 -1 (-1050 1200)(-1050 1250);
WIRE 17 -1 (-1050 1150)(-1050 1200);
WIRE 17 -1 (-1050 1100)(-1050 1150);
WIRE 17 -1 (-1050 1050)(-1050 1100);
WIRE 17 -1 (-1050 1000)(-1050 1050);
WIRE 17 -1 (-1050 950)(-1050 1000);
WIRE 17 -1 (-1050 900)(-1050 950);
WIRE 17 -1 (-1050 850)(-1050 900);
WIRE 17 -1 (-1050 800)(-1050 850);
WIRE 17 -1 (1700 2050)(1700 2150);
WIRE 17 -1 (1700 2150)(1700 2250);
WIRE 17 -1 (1700 2250)(1700 2350);
WIRE 17 -1 (1700 2450)(1700 2350);
WIRE 17 -1 (1700 2450)(1700 2550);
WIRE 17 -1 (1700 2550)(1700 2650);
WIRE 17 -1 (1700 2650)(1700 2750);
WIRE 17 -1 (1700 2750)(1700 2850);
WIRE 17 -1 (1700 2850)(1700 2950);
WIRE 17 -1 (1700 2950)(2725 2950);
FORCEPROP 2 LAST SIG_NAME M_E_CPU1_SB_DQS_DP<9:0>
J 0
(1940 2960);
DISPLAY 0.680851 (1940 2960);
PAINT WHITE (1940 2960);
WIRE 17 -1 (1700 3100)(1700 3200);
WIRE 17 -1 (1700 3200)(1700 3300);
WIRE 17 -1 (1700 3300)(1700 3400);
WIRE 17 -1 (1700 3500)(1700 3400);
WIRE 17 -1 (1700 3500)(1700 3600);
WIRE 17 -1 (1700 3600)(1700 3700);
WIRE 17 -1 (1700 3700)(1700 3800);
WIRE 17 -1 (1700 3800)(1700 3900);
WIRE 17 -1 (1700 3900)(1700 4000);
WIRE 17 -1 (1700 4000)(2725 4000);
FORCEPROP 2 LAST SIG_NAME M_E_CPU1_SA_DQS_DP<9:0>
J 0
(1940 4010);
DISPLAY 0.680851 (1940 4010);
PAINT WHITE (1940 4010);
WIRE 17 -1 (1875 2000)(1875 2100);
WIRE 17 -1 (1875 2100)(1875 2200);
WIRE 17 -1 (1875 2200)(1875 2300);
WIRE 17 -1 (1875 2400)(1875 2300);
WIRE 17 -1 (1875 2400)(1875 2500);
WIRE 17 -1 (1875 2500)(1875 2600);
WIRE 17 -1 (1875 2600)(1875 2700);
WIRE 17 -1 (1875 2700)(1875 2800);
WIRE 17 -1 (1875 2800)(1875 2900);
WIRE 17 -1 (1875 2900)(2725 2900);
FORCEPROP 2 LAST SIG_NAME M_E_CPU1_SB_DQS_DN<9:0>
J 0
(1940 2910);
DISPLAY 0.680851 (1940 2910);
PAINT WHITE (1940 2910);
WIRE 17 -1 (1875 3050)(1875 3150);
WIRE 17 -1 (1875 3150)(1875 3250);
WIRE 17 -1 (1875 3250)(1875 3350);
WIRE 17 -1 (1875 3450)(1875 3350);
WIRE 17 -1 (1875 3450)(1875 3550);
WIRE 17 -1 (1875 3550)(1875 3650);
WIRE 17 -1 (1875 3650)(1875 3750);
WIRE 17 -1 (1875 3750)(1875 3850);
WIRE 17 -1 (1875 3850)(1875 3950);
WIRE 17 -1 (1875 3950)(2725 3950);
FORCEPROP 2 LAST SIG_NAME M_E_CPU1_SA_DQS_DN<9:0>
J 0
(1940 3960);
DISPLAY 0.680851 (1940 3960);
PAINT WHITE (1940 3960);
WIRE 16 -1 (625 200)(625 375);
WIRE 16 -1 (1625 375)(1625 325);
WIRE 16 -1 (3325 4475)(3325 3975);
WIRE 16 -1 (-3575 1800)(-3575 1525);
WIRE 16 -1 (-2525 -350)(-2525 -275);
WIRE 16 -1 (625 0)(625 -225);
WIRE 16 -1 (2250 -225)(2250 -150);
WIRE 16 -1 (3325 325)(3325 725);
WIRE 16 -1 (5025 625)(5025 325);
WIRE 16 -1 (5025 675)(5025 625);
WIRE 16 -1 (4775 625)(5025 625);
WIRE 16 -1 (-3575 1525)(-2525 1525);
WIRE 16 -1 (-4025 1275)(-3825 1275);
WIRE 16 -1 (-4025 1275)(-4025 1375);
WIRE 16 -1 (-4025 1375)(-2525 1375);
FORCEPROP 2 LAST SIG_NAME I3C_SPD_DDREFGH_CPU1_LVC1_SCL_R1
J 0
(-3585 1385);
DISPLAY 0.680851 (-3585 1385);
PAINT WHITE (-3585 1385);
WIRE 16 -1 (-2525 1425)(-3550 1425);
FORCEPROP 2 LAST SIG_NAME I3C_SPD_DDREFGH_CPU1_LVC1_SDA
J 0
(-3535 1435);
DISPLAY 0.680851 (-3535 1435);
PAINT WHITE (-3535 1435);
WIRE 16 -1 (-2525 1475)(-3550 1475);
FORCEPROP 2 LAST SIG_NAME PD_CHE_CPU1_DIMM1_SAA
J 0
(-3535 1485);
DISPLAY 0.680851 (-3535 1485);
PAINT WHITE (-3535 1485);
WIRE 16 -1 (-2525 1625)(-3625 1625);
FORCEPROP 2 LAST SIG_NAME M_E_CPU1_ALERT_N
J 0
(-3537 1634);
DISPLAY 0.680851 (-3537 1634);
PAINT WHITE (-3537 1634);
WIRE 16 -1 (-2900 1675)(-2525 1675);
WIRE 16 -1 (-2900 1725)(-3625 1725);
FORCEPROP 2 LAST SIG_NAME RST_M_EF_CPU1_FPGA_N
J 0
(-3537 1734);
DISPLAY 0.680851 (-3537 1734);
PAINT WHITE (-3537 1734);
WIRE 16 -1 (-2900 1725)(-2900 1675);
WIRE 16 -1 (-2425 1225)(-2475 1225);
WIRE 16 -1 (-2425 1275)(-3625 1275);
FORCEPROP 2 LAST SIG_NAME I3C_SPD_DDREFGH_CPU1_LVC1_SCL
J 0
(-3485 1285);
DISPLAY 0.680851 (-3485 1285);
PAINT WHITE (-3485 1285);
WIRE 16 -1 (-2425 1275)(-2425 1225);
WIRE 16 -1 (1500 2525)(1600 2525);
WIRE 16 -1 (1500 2475)(1775 2475);
WIRE 16 -1 (1500 3925)(1775 3925);
WIRE 16 -1 (1500 3825)(1775 3825);
WIRE 16 -1 (1500 3725)(1775 3725);
WIRE 16 -1 (1500 3625)(1775 3625);
WIRE 16 -1 (1500 3525)(1775 3525);
WIRE 16 -1 (1500 3425)(1775 3425);
WIRE 16 -1 (1500 3325)(1775 3325);
WIRE 16 -1 (1500 3225)(1775 3225);
WIRE 16 -1 (1500 3125)(1775 3125);
WIRE 16 -1 (1500 3025)(1775 3025);
WIRE 16 -1 (1500 2875)(1775 2875);
WIRE 16 -1 (1500 2775)(1775 2775);
WIRE 16 -1 (1500 2675)(1775 2675);
WIRE 16 -1 (1500 2575)(1775 2575);
WIRE 16 -1 (1500 2375)(1775 2375);
WIRE 16 -1 (1500 2275)(1775 2275);
WIRE 16 -1 (1500 2075)(1775 2075);
WIRE 16 -1 (1500 2175)(1775 2175);
WIRE 16 -1 (1500 1975)(1775 1975);
WIRE 16 -1 (1500 3975)(1600 3975);
WIRE 16 -1 (1500 3875)(1600 3875);
WIRE 16 -1 (1500 3775)(1600 3775);
WIRE 16 -1 (1500 3675)(1600 3675);
WIRE 16 -1 (1500 3575)(1600 3575);
WIRE 16 -1 (1500 3475)(1600 3475);
WIRE 16 -1 (1500 3375)(1600 3375);
WIRE 16 -1 (1500 3275)(1600 3275);
WIRE 16 -1 (1500 3175)(1600 3175);
WIRE 16 -1 (1500 3075)(1600 3075);
WIRE 16 -1 (1500 2925)(1600 2925);
WIRE 16 -1 (1500 2825)(1600 2825);
WIRE 16 -1 (1500 2725)(1600 2725);
WIRE 16 -1 (1500 2625)(1600 2625);
WIRE 16 -1 (1500 2425)(1600 2425);
WIRE 16 -1 (1500 2325)(1600 2325);
WIRE 16 -1 (1500 2225)(1600 2225);
WIRE 16 -1 (1500 2125)(1600 2125);
WIRE 16 -1 (1500 2025)(1600 2025);
WIRE 16 -1 (-2525 1025)(-3625 1025);
FORCEPROP 2 LAST SIG_NAME TP_CHE_CPU1_DIMM1_FRU_6
J 0
(-3537 1034);
DISPLAY 0.680851 (-3537 1034);
PAINT WHITE (-3537 1034);
WIRE 16 -1 (-2525 975)(-3625 975);
FORCEPROP 2 LAST SIG_NAME TP_CHE_CPU1_DIMM1_FRU_5
J 0
(-3537 984);
DISPLAY 0.680851 (-3537 984);
PAINT WHITE (-3537 984);
WIRE 16 -1 (-2525 1125)(-3625 1125);
FORCEPROP 2 LAST SIG_NAME PWRGD_CHE_CPU1_DIMM1
J 0
(-3537 1134);
DISPLAY 0.680851 (-3537 1134);
PAINT WHITE (-3537 1134);
WIRE 16 -1 (-2525 825)(-3625 825);
FORCEPROP 2 LAST SIG_NAME TP_CHE_CPU1_DIMM1_FRU_2
J 0
(-3537 834);
DISPLAY 0.680851 (-3537 834);
PAINT WHITE (-3537 834);
WIRE 16 -1 (-2525 875)(-3625 875);
FORCEPROP 2 LAST SIG_NAME TP_CHE_CPU1_DIMM1_FRU_3
J 0
(-3537 884);
DISPLAY 0.680851 (-3537 884);
PAINT WHITE (-3537 884);
WIRE 16 -1 (-1325 2275)(-1150 2275);
WIRE 16 -1 (3575 3975)(3325 3975);
WIRE 16 -1 (3325 3975)(3325 3925);
WIRE 16 -1 (3325 3925)(3575 3925);
WIRE 16 -1 (3325 3925)(3325 3875);
WIRE 16 -1 (3575 3875)(3325 3875);
WIRE 16 -1 (-2700 3275)(-2525 3275);
WIRE 16 -1 (-2525 3175)(-3625 3175);
FORCEPROP 2 LAST SIG_NAME M_E_CPU1_SA_PAR
J 0
(-3537 3184);
DISPLAY 0.680851 (-3537 3184);
PAINT WHITE (-3537 3184);
WIRE 16 -1 (-2525 3125)(-3625 3125);
FORCEPROP 2 LAST SIG_NAME M_E_CPU1_SB_PAR
J 0
(-3537 3134);
DISPLAY 0.680851 (-3537 3134);
PAINT WHITE (-3537 3134);
WIRE 16 -1 (-1325 2075)(-1150 2075);
WIRE 16 -1 (-1325 2025)(-1150 2025);
WIRE 16 -1 (-1325 1975)(-1150 1975);
WIRE 16 -1 (-1325 1725)(-1150 1725);
WIRE 16 -1 (-2700 1875)(-2525 1875);
WIRE 16 -1 (-2525 2675)(-3625 2675);
FORCEPROP 2 LAST SIG_NAME M_E_CPU1_CLK_DN<0>
J 0
(-3537 2684);
DISPLAY 0.680851 (-3537 2684);
PAINT WHITE (-3537 2684);
WIRE 16 -1 (-1325 2725)(-1150 2725);
WIRE 16 -1 (-1325 2225)(-1150 2225);
WIRE 16 -1 (-2525 725)(-3625 725);
FORCEPROP 2 LAST SIG_NAME TP_CHE_CPU1_DIMM1_FRU_0
J 0
(-3537 734);
DISPLAY 0.680851 (-3537 734);
PAINT WHITE (-3537 734);
WIRE 16 -1 (-2525 775)(-3625 775);
FORCEPROP 2 LAST SIG_NAME TP_CHE_CPU1_DIMM1_FRU_1
J 0
(-3537 784);
DISPLAY 0.680851 (-3537 784);
PAINT WHITE (-3537 784);
WIRE 16 -1 (-2525 925)(-3625 925);
FORCEPROP 2 LAST SIG_NAME TP_CHE_CPU1_DIMM1_FRU_4
J 0
(-3537 934);
DISPLAY 0.680851 (-3537 934);
PAINT WHITE (-3537 934);
WIRE 16 -1 (-2525 525)(-3625 525);
FORCEPROP 2 LAST SIG_NAME M_E_CPU1_SB_RSP<0>
J 0
(-3537 534);
DISPLAY 0.680851 (-3537 534);
PAINT WHITE (-3537 534);
WIRE 16 -1 (-2525 575)(-3625 575);
FORCEPROP 2 LAST SIG_NAME M_E_CPU1_SA_RSP<0>
J 0
(-3537 584);
DISPLAY 0.680851 (-3537 584);
PAINT WHITE (-3537 584);
WIRE 16 -1 (-1325 775)(-1150 775);
WIRE 16 -1 (-1325 825)(-1150 825);
WIRE 16 -1 (-1325 875)(-1150 875);
WIRE 16 -1 (-1325 925)(-1150 925);
WIRE 16 -1 (-1325 975)(-1150 975);
WIRE 16 -1 (-1325 1025)(-1150 1025);
WIRE 16 -1 (-1325 1075)(-1150 1075);
WIRE 16 -1 (-1325 1125)(-1150 1125);
WIRE 16 -1 (-1325 1175)(-1150 1175);
WIRE 16 -1 (-1325 1225)(-1150 1225);
WIRE 16 -1 (-1325 1275)(-1150 1275);
WIRE 16 -1 (-1325 1325)(-1150 1325);
WIRE 16 -1 (-1325 1375)(-1150 1375);
WIRE 16 -1 (-1325 1425)(-1150 1425);
WIRE 16 -1 (-1325 1475)(-1150 1475);
WIRE 16 -1 (-1325 1525)(-1150 1525);
WIRE 16 -1 (-1325 1575)(-1150 1575);
WIRE 16 -1 (-1325 1625)(-1150 1625);
WIRE 16 -1 (-1325 1675)(-1150 1675);
WIRE 16 -1 (-1325 1775)(-1150 1775);
WIRE 16 -1 (-1325 1825)(-1150 1825);
WIRE 16 -1 (-1325 1875)(-1150 1875);
WIRE 16 -1 (-1325 1925)(-1150 1925);
WIRE 16 -1 (-1325 2125)(-1150 2125);
WIRE 16 -1 (-1325 2175)(-1150 2175);
WIRE 16 -1 (-1325 2325)(-1150 2325);
WIRE 16 -1 (-1325 2425)(-1150 2425);
WIRE 16 -1 (-1325 2475)(-1150 2475);
WIRE 16 -1 (-1325 2525)(-1150 2525);
WIRE 16 -1 (-1325 2575)(-1150 2575);
WIRE 16 -1 (-1325 2625)(-1150 2625);
WIRE 16 -1 (-1325 2675)(-1150 2675);
WIRE 16 -1 (-1325 2775)(-1150 2775);
WIRE 16 -1 (-1325 2825)(-1150 2825);
WIRE 16 -1 (-1325 2875)(-1150 2875);
WIRE 16 -1 (-1325 2925)(-1150 2925);
WIRE 16 -1 (-1325 2975)(-1150 2975);
WIRE 16 -1 (-1325 3025)(-1150 3025);
WIRE 16 -1 (-1325 3075)(-1150 3075);
WIRE 16 -1 (-1325 3125)(-1150 3125);
WIRE 16 -1 (-1325 3175)(-1150 3175);
WIRE 16 -1 (-1325 3225)(-1150 3225);
WIRE 16 -1 (-1325 3275)(-1150 3275);
WIRE 16 -1 (-1325 3325)(-1150 3325);
WIRE 16 -1 (-1325 3375)(-1150 3375);
WIRE 16 -1 (-1325 3425)(-1150 3425);
WIRE 16 -1 (-1325 3475)(-1150 3475);
WIRE 16 -1 (-1325 3525)(-1150 3525);
WIRE 16 -1 (-1325 3575)(-1150 3575);
WIRE 16 -1 (-1325 3625)(-1150 3625);
WIRE 16 -1 (-1325 3675)(-1150 3675);
WIRE 16 -1 (-1325 3725)(-1150 3725);
WIRE 16 -1 (-1325 3775)(-1150 3775);
WIRE 16 -1 (-1325 3825)(-1150 3825);
WIRE 16 -1 (-1325 3875)(-1150 3875);
WIRE 16 -1 (-1325 3925)(-1150 3925);
WIRE 16 -1 (-2525 2875)(-3625 2875);
FORCEPROP 2 LAST SIG_NAME M_E_CPU1_SB_CS_N<1>
J 0
(-3537 2884);
DISPLAY 0.680851 (-3537 2884);
PAINT WHITE (-3537 2884);
WIRE 16 -1 (-2525 3025)(-3625 3025);
FORCEPROP 2 LAST SIG_NAME M_E_CPU1_SA_CS_N<1>
J 0
(-3537 3034);
DISPLAY 0.680851 (-3537 3034);
PAINT WHITE (-3537 3034);
WIRE 16 -1 (-2525 2825)(-3625 2825);
FORCEPROP 2 LAST SIG_NAME M_E_CPU1_SB_CS_N<0>
J 0
(-3537 2834);
DISPLAY 0.680851 (-3537 2834);
PAINT WHITE (-3537 2834);
WIRE 16 -1 (-2525 2975)(-3625 2975);
FORCEPROP 2 LAST SIG_NAME M_E_CPU1_SA_CS_N<0>
J 0
(-3537 2984);
DISPLAY 0.680851 (-3537 2984);
PAINT WHITE (-3537 2984);
WIRE 16 -1 (-2525 2725)(-3625 2725);
FORCEPROP 2 LAST SIG_NAME M_E_CPU1_CLK_DP<0>
J 0
(-3537 2734);
DISPLAY 0.680851 (-3537 2734);
PAINT WHITE (-3537 2734);
WIRE 16 -1 (-2700 1775)(-2525 1775);
WIRE 16 -1 (-2700 1825)(-2525 1825);
WIRE 16 -1 (-2700 1925)(-2525 1925);
WIRE 16 -1 (-2700 1975)(-2525 1975);
WIRE 16 -1 (-2700 2025)(-2525 2025);
WIRE 16 -1 (-2700 2075)(-2525 2075);
WIRE 16 -1 (-2700 2225)(-2525 2225);
WIRE 16 -1 (-2700 2325)(-2525 2325);
WIRE 16 -1 (-2700 2375)(-2525 2375);
WIRE 16 -1 (-2700 2475)(-2525 2475);
WIRE 16 -1 (-2700 2525)(-2525 2525);
WIRE 16 -1 (-2700 3575)(-2525 3575);
WIRE 16 -1 (-2700 3975)(-2525 3975);
WIRE 16 -1 (-2700 3525)(-2525 3525);
WIRE 16 -1 (-2700 3925)(-2525 3925);
WIRE 16 -1 (-2700 3475)(-2525 3475);
WIRE 16 -1 (-2700 3875)(-2525 3875);
WIRE 16 -1 (-2700 3425)(-2525 3425);
WIRE 16 -1 (-2700 3825)(-2525 3825);
WIRE 16 -1 (-2700 3375)(-2525 3375);
WIRE 16 -1 (-2700 3775)(-2525 3775);
WIRE 16 -1 (-2700 3325)(-2525 3325);
WIRE 16 -1 (-2700 3725)(-2525 3725);
WIRE 16 -1 (-2700 3675)(-2525 3675);
WIRE 16 -1 (-2700 2125)(-2525 2125);
WIRE 16 -1 (-2700 2275)(-2525 2275);
WIRE 16 -1 (-2700 2425)(-2525 2425);
WIRE 16 -1 (-2700 2575)(-2525 2575);
WIRE 16 -1 (-1325 3975)(-1150 3975);
WIRE 16 -1 (4775 3975)(5025 3975);
WIRE 16 -1 (4775 3925)(5025 3925);
WIRE 16 -1 (5025 3975)(5025 3925);
WIRE 16 -1 (4775 3875)(5025 3875);
WIRE 16 -1 (5025 3925)(5025 3875);
WIRE 16 -1 (4775 3825)(5025 3825);
WIRE 16 -1 (5025 3875)(5025 3825);
WIRE 16 -1 (4775 3775)(5025 3775);
WIRE 16 -1 (5025 3825)(5025 3775);
WIRE 16 -1 (4775 3725)(5025 3725);
WIRE 16 -1 (5025 3775)(5025 3725);
WIRE 16 -1 (4775 3675)(5025 3675);
WIRE 16 -1 (5025 3725)(5025 3675);
WIRE 16 -1 (4775 3625)(5025 3625);
WIRE 16 -1 (5025 3675)(5025 3625);
WIRE 16 -1 (4775 3575)(5025 3575);
WIRE 16 -1 (5025 3625)(5025 3575);
WIRE 16 -1 (4775 3525)(5025 3525);
WIRE 16 -1 (5025 3575)(5025 3525);
WIRE 16 -1 (4775 3475)(5025 3475);
WIRE 16 -1 (5025 3525)(5025 3475);
WIRE 16 -1 (4775 3425)(5025 3425);
WIRE 16 -1 (5025 3475)(5025 3425);
WIRE 16 -1 (4775 3375)(5025 3375);
WIRE 16 -1 (5025 3425)(5025 3375);
WIRE 16 -1 (4775 3325)(5025 3325);
WIRE 16 -1 (5025 3375)(5025 3325);
WIRE 16 -1 (4775 3275)(5025 3275);
WIRE 16 -1 (5025 3325)(5025 3275);
WIRE 16 -1 (4775 3225)(5025 3225);
WIRE 16 -1 (5025 3225)(5025 3275);
WIRE 16 -1 (4775 3175)(5025 3175);
WIRE 16 -1 (5025 3225)(5025 3175);
WIRE 16 -1 (5025 3125)(4775 3125);
WIRE 16 -1 (5025 3175)(5025 3125);
WIRE 16 -1 (5025 3075)(4775 3075);
WIRE 16 -1 (5025 3125)(5025 3075);
WIRE 16 -1 (4775 3025)(5025 3025);
WIRE 16 -1 (5025 3075)(5025 3025);
WIRE 16 -1 (4775 2975)(5025 2975);
WIRE 16 -1 (5025 3025)(5025 2975);
WIRE 16 -1 (4775 2925)(5025 2925);
WIRE 16 -1 (5025 2975)(5025 2925);
WIRE 16 -1 (4775 2875)(5025 2875);
WIRE 16 -1 (5025 2925)(5025 2875);
WIRE 16 -1 (4775 2825)(5025 2825);
WIRE 16 -1 (5025 2875)(5025 2825);
WIRE 16 -1 (4775 2775)(5025 2775);
WIRE 16 -1 (5025 2825)(5025 2775);
WIRE 16 -1 (4775 2725)(5025 2725);
WIRE 16 -1 (5025 2725)(5025 2775);
WIRE 16 -1 (4775 2675)(5025 2675);
WIRE 16 -1 (5025 2725)(5025 2675);
WIRE 16 -1 (5025 2625)(4775 2625);
WIRE 16 -1 (5025 2675)(5025 2625);
WIRE 16 -1 (5025 2575)(4775 2575);
WIRE 16 -1 (5025 2625)(5025 2575);
WIRE 16 -1 (4775 2525)(5025 2525);
WIRE 16 -1 (5025 2575)(5025 2525);
WIRE 16 -1 (4775 2475)(5025 2475);
WIRE 16 -1 (5025 2525)(5025 2475);
WIRE 16 -1 (4775 2425)(5025 2425);
WIRE 16 -1 (5025 2475)(5025 2425);
WIRE 16 -1 (4775 2375)(5025 2375);
WIRE 16 -1 (5025 2425)(5025 2375);
WIRE 16 -1 (4775 2325)(5025 2325);
WIRE 16 -1 (5025 2375)(5025 2325);
WIRE 16 -1 (4775 2275)(5025 2275);
WIRE 16 -1 (5025 2325)(5025 2275);
WIRE 16 -1 (4775 2225)(5025 2225);
WIRE 16 -1 (5025 2225)(5025 2275);
WIRE 16 -1 (4775 2175)(5025 2175);
WIRE 16 -1 (5025 2225)(5025 2175);
WIRE 16 -1 (5025 2125)(4775 2125);
WIRE 16 -1 (5025 2175)(5025 2125);
WIRE 16 -1 (5025 2075)(4775 2075);
WIRE 16 -1 (5025 2125)(5025 2075);
WIRE 16 -1 (4775 2025)(5025 2025);
WIRE 16 -1 (5025 2075)(5025 2025);
WIRE 16 -1 (4775 1975)(5025 1975);
WIRE 16 -1 (5025 2025)(5025 1975);
WIRE 16 -1 (4775 1925)(5025 1925);
WIRE 16 -1 (5025 1975)(5025 1925);
WIRE 16 -1 (4775 1875)(5025 1875);
WIRE 16 -1 (5025 1925)(5025 1875);
WIRE 16 -1 (4775 1825)(5025 1825);
WIRE 16 -1 (5025 1875)(5025 1825);
WIRE 16 -1 (4775 1775)(5025 1775);
WIRE 16 -1 (5025 1825)(5025 1775);
WIRE 16 -1 (4775 1725)(5025 1725);
WIRE 16 -1 (5025 1725)(5025 1775);
WIRE 16 -1 (4775 1675)(5025 1675);
WIRE 16 -1 (5025 1725)(5025 1675);
WIRE 16 -1 (5025 1625)(4775 1625);
WIRE 16 -1 (5025 1675)(5025 1625);
WIRE 16 -1 (5025 1575)(4775 1575);
WIRE 16 -1 (5025 1625)(5025 1575);
WIRE 16 -1 (5025 1525)(4775 1525);
WIRE 16 -1 (5025 1575)(5025 1525);
WIRE 16 -1 (5025 1475)(4775 1475);
WIRE 16 -1 (5025 1525)(5025 1475);
WIRE 16 -1 (4775 1425)(5025 1425);
WIRE 16 -1 (5025 1425)(5025 1475);
WIRE 16 -1 (5025 1375)(4775 1375);
WIRE 16 -1 (5025 1375)(5025 1425);
WIRE 16 -1 (5025 1325)(4775 1325);
WIRE 16 -1 (5025 1375)(5025 1325);
WIRE 16 -1 (5025 1275)(4775 1275);
WIRE 16 -1 (5025 1325)(5025 1275);
WIRE 16 -1 (4775 1225)(5025 1225);
WIRE 16 -1 (5025 1275)(5025 1225);
WIRE 16 -1 (4775 1175)(5025 1175);
WIRE 16 -1 (5025 1225)(5025 1175);
WIRE 16 -1 (4775 1125)(5025 1125);
WIRE 16 -1 (5025 1175)(5025 1125);
WIRE 16 -1 (4775 1075)(5025 1075);
WIRE 16 -1 (5025 1125)(5025 1075);
WIRE 16 -1 (4775 1025)(5025 1025);
WIRE 16 -1 (5025 1075)(5025 1025);
WIRE 16 -1 (4775 975)(5025 975);
WIRE 16 -1 (5025 1025)(5025 975);
WIRE 16 -1 (4775 925)(5025 925);
WIRE 16 -1 (5025 975)(5025 925);
WIRE 16 -1 (4775 875)(5025 875);
WIRE 16 -1 (5025 875)(5025 925);
WIRE 16 -1 (4775 825)(5025 825);
WIRE 16 -1 (5025 875)(5025 825);
WIRE 16 -1 (4775 725)(5025 725);
WIRE 16 -1 (5025 825)(5025 725);
WIRE 16 -1 (5025 725)(5025 675);
WIRE 16 -1 (4775 675)(5025 675);
WIRE 16 -1 (3575 3825)(3325 3825);
WIRE 16 -1 (3325 3775)(3325 3825);
WIRE 16 -1 (3325 3775)(3575 3775);
WIRE 16 -1 (3325 3725)(3325 3775);
WIRE 16 -1 (3575 3725)(3325 3725);
WIRE 16 -1 (3325 3675)(3325 3725);
WIRE 16 -1 (3325 3675)(3575 3675);
WIRE 16 -1 (3325 3625)(3325 3675);
WIRE 16 -1 (3325 3625)(3575 3625);
WIRE 16 -1 (3325 3575)(3575 3575);
WIRE 16 -1 (3325 3575)(3325 3625);
WIRE 16 -1 (3325 3525)(3325 3575);
WIRE 16 -1 (3325 3525)(3575 3525);
WIRE 16 -1 (3325 3475)(3325 3525);
WIRE 16 -1 (3325 3475)(3575 3475);
WIRE 16 -1 (3325 3425)(3325 3475);
WIRE 16 -1 (3325 3425)(3575 3425);
WIRE 16 -1 (3325 3375)(3325 3425);
WIRE 16 -1 (3325 3375)(3575 3375);
WIRE 16 -1 (3325 3325)(3325 3375);
WIRE 16 -1 (3325 3325)(3575 3325);
WIRE 16 -1 (3325 3275)(3325 3325);
WIRE 16 -1 (3325 3275)(3575 3275);
WIRE 16 -1 (3325 3225)(3325 3275);
WIRE 16 -1 (3575 3225)(3325 3225);
WIRE 16 -1 (3325 3175)(3325 3225);
WIRE 16 -1 (3325 3175)(3575 3175);
WIRE 16 -1 (3325 3125)(3325 3175);
WIRE 16 -1 (3325 3125)(3575 3125);
WIRE 16 -1 (3325 3075)(3325 3125);
WIRE 16 -1 (3325 3075)(3575 3075);
WIRE 16 -1 (3325 3025)(3575 3025);
WIRE 16 -1 (3325 3025)(3325 3075);
WIRE 16 -1 (3325 2975)(3325 3025);
WIRE 16 -1 (3325 2975)(3575 2975);
WIRE 16 -1 (3325 2925)(3325 2975);
WIRE 16 -1 (3325 2925)(3575 2925);
WIRE 16 -1 (3325 2875)(3325 2925);
WIRE 16 -1 (3325 2875)(3575 2875);
WIRE 16 -1 (3325 2825)(3325 2875);
WIRE 16 -1 (3325 2825)(3575 2825);
WIRE 16 -1 (3325 2775)(3325 2825);
WIRE 16 -1 (3325 2775)(3575 2775);
WIRE 16 -1 (3325 2725)(3325 2775);
WIRE 16 -1 (3575 2725)(3325 2725);
WIRE 16 -1 (3325 2675)(3325 2725);
WIRE 16 -1 (3325 2675)(3575 2675);
WIRE 16 -1 (3325 2625)(3325 2675);
WIRE 16 -1 (3325 2625)(3575 2625);
WIRE 16 -1 (3325 2575)(3325 2625);
WIRE 16 -1 (3325 2575)(3575 2575);
WIRE 16 -1 (3325 2525)(3575 2525);
WIRE 16 -1 (3325 2525)(3325 2575);
WIRE 16 -1 (3325 2475)(3325 2525);
WIRE 16 -1 (3325 2475)(3575 2475);
WIRE 16 -1 (3325 2425)(3325 2475);
WIRE 16 -1 (3325 2425)(3575 2425);
WIRE 16 -1 (3325 2375)(3325 2425);
WIRE 16 -1 (3325 2375)(3575 2375);
WIRE 16 -1 (3325 2325)(3325 2375);
WIRE 16 -1 (3325 2325)(3575 2325);
WIRE 16 -1 (3325 2275)(3325 2325);
WIRE 16 -1 (3325 2275)(3575 2275);
WIRE 16 -1 (3325 2225)(3325 2275);
WIRE 16 -1 (3575 2225)(3325 2225);
WIRE 16 -1 (3325 2175)(3325 2225);
WIRE 16 -1 (3325 2175)(3575 2175);
WIRE 16 -1 (3325 2125)(3325 2175);
WIRE 16 -1 (3325 2125)(3575 2125);
WIRE 16 -1 (3325 2075)(3325 2125);
WIRE 16 -1 (3325 2075)(3575 2075);
WIRE 16 -1 (3325 2025)(3575 2025);
WIRE 16 -1 (3325 2025)(3325 2075);
WIRE 16 -1 (3325 1975)(3325 2025);
WIRE 16 -1 (3325 1975)(3575 1975);
WIRE 16 -1 (3325 1925)(3325 1975);
WIRE 16 -1 (3325 1925)(3575 1925);
WIRE 16 -1 (3325 1875)(3325 1925);
WIRE 16 -1 (3325 1875)(3575 1875);
WIRE 16 -1 (3325 1825)(3325 1875);
WIRE 16 -1 (3325 1825)(3575 1825);
WIRE 16 -1 (3325 1775)(3325 1825);
WIRE 16 -1 (3325 1775)(3575 1775);
WIRE 16 -1 (3325 1725)(3325 1775);
WIRE 16 -1 (3575 1725)(3325 1725);
WIRE 16 -1 (3325 1675)(3325 1725);
WIRE 16 -1 (3325 1675)(3575 1675);
WIRE 16 -1 (3325 1625)(3325 1675);
WIRE 16 -1 (3325 1625)(3575 1625);
WIRE 16 -1 (3325 1575)(3325 1625);
WIRE 16 -1 (3325 1575)(3575 1575);
WIRE 16 -1 (3325 1525)(3575 1525);
WIRE 16 -1 (3325 1525)(3325 1575);
WIRE 16 -1 (3325 1475)(3325 1525);
WIRE 16 -1 (3325 1475)(3575 1475);
WIRE 16 -1 (3325 1425)(3325 1475);
WIRE 16 -1 (3325 1425)(3575 1425);
WIRE 16 -1 (3325 1375)(3325 1425);
WIRE 16 -1 (3325 1375)(3575 1375);
WIRE 16 -1 (3325 1325)(3325 1375);
WIRE 16 -1 (3325 1325)(3575 1325);
WIRE 16 -1 (3325 1275)(3325 1325);
WIRE 16 -1 (3325 1275)(3575 1275);
WIRE 16 -1 (3325 1225)(3325 1275);
WIRE 16 -1 (3575 1225)(3325 1225);
WIRE 16 -1 (3325 1175)(3325 1225);
WIRE 16 -1 (3325 1175)(3575 1175);
WIRE 16 -1 (3325 1125)(3325 1175);
WIRE 16 -1 (3325 1125)(3575 1125);
WIRE 16 -1 (3325 1075)(3325 1125);
WIRE 16 -1 (3325 1075)(3575 1075);
WIRE 16 -1 (3325 1025)(3325 1075);
WIRE 16 -1 (3325 1025)(3575 1025);
WIRE 16 -1 (3325 975)(3575 975);
WIRE 16 -1 (3325 975)(3325 1025);
WIRE 16 -1 (3325 925)(3325 975);
WIRE 16 -1 (3325 925)(3575 925);
WIRE 16 -1 (3325 875)(3325 925);
WIRE 16 -1 (3325 875)(3575 875);
WIRE 16 -1 (3325 825)(3325 875);
WIRE 16 -1 (3325 825)(3575 825);
WIRE 16 -1 (3325 775)(3325 825);
WIRE 16 -1 (3325 775)(3575 775);
WIRE 16 -1 (3325 725)(3325 775);
WIRE 16 -1 (3325 725)(3575 725);
WIRE 16 -1 (-2525 25)(-3625 25);
FORCEPROP 2 LAST SIG_NAME PD_CHE_CPU1_DIMM1_SAA
J 0
(-3537 34);
DISPLAY 0.680851 (-3537 34);
PAINT WHITE (-3537 34);
WIRE 16 -1 (-2525 -75)(-2525 25);
WIRE 16 -1 (1625 325)(1625 200);
WIRE 16 -1 (2250 325)(1625 325);
WIRE 16 -1 (2250 200)(2250 325);
WIRE 16 -1 (2250 -150)(2250 0);
WIRE 16 -1 (2250 -150)(1625 -150);
WIRE 16 -1 (1625 -150)(1625 0);
WIRE 16 3135 (275 600)(275 -700);
WIRE 16 3135 (2875 600)(275 600);
WIRE 16 3135 (275 -700)(2875 -700);
WIRE 16 3135 (2875 -700)(2875 600);
DOT 1 (3325 2875);
DOT 1 (3325 3175);
DOT 1 (3325 2775);
DOT 1 (5025 3925);
DOT 1 (5025 3875);
DOT 1 (5025 3825);
DOT 1 (5025 3775);
DOT 1 (5025 3725);
DOT 1 (5025 3625);
DOT 1 (5025 3675);
DOT 1 (5025 3575);
DOT 1 (5025 3525);
DOT 1 (5025 3475);
DOT 1 (5025 3425);
DOT 1 (5025 3375);
DOT 1 (5025 3325);
DOT 1 (5025 3275);
DOT 1 (5025 3225);
DOT 1 (5025 3175);
DOT 1 (5025 3125);
DOT 1 (5025 3075);
DOT 1 (5025 3025);
DOT 1 (5025 2975);
DOT 1 (5025 2925);
DOT 1 (5025 2875);
DOT 1 (5025 2825);
DOT 1 (5025 2775);
DOT 1 (5025 2725);
DOT 1 (5025 2675);
DOT 1 (5025 2625);
DOT 1 (5025 2575);
DOT 1 (5025 2525);
DOT 1 (5025 2475);
DOT 1 (5025 2425);
DOT 1 (5025 2375);
DOT 1 (5025 2325);
DOT 1 (5025 2275);
DOT 1 (5025 2225);
DOT 1 (5025 2175);
DOT 1 (5025 2125);
DOT 1 (5025 2075);
DOT 1 (5025 2025);
DOT 1 (5025 1975);
DOT 1 (5025 1925);
DOT 1 (5025 1875);
DOT 1 (5025 1825);
DOT 1 (5025 1775);
DOT 1 (5025 1725);
DOT 1 (5025 1675);
DOT 1 (5025 1575);
DOT 1 (5025 1625);
DOT 1 (5025 1525);
DOT 1 (5025 1475);
DOT 1 (5025 1425);
DOT 1 (5025 1375);
DOT 1 (5025 1325);
DOT 1 (5025 1275);
DOT 1 (5025 1225);
DOT 1 (5025 1175);
DOT 1 (5025 1125);
DOT 1 (5025 1075);
DOT 1 (5025 1025);
DOT 1 (5025 975);
DOT 1 (5025 925);
DOT 1 (5025 875);
DOT 1 (5025 825);
DOT 1 (3325 3925);
DOT 1 (3325 3975);
DOT 1 (3325 3775);
DOT 1 (3325 3725);
DOT 1 (3325 3625);
DOT 1 (3325 3675);
DOT 1 (3325 3575);
DOT 1 (3325 3525);
DOT 1 (3325 3475);
DOT 1 (3325 3425);
DOT 1 (3325 3375);
DOT 1 (3325 3325);
DOT 1 (3325 3275);
DOT 1 (3325 3225);
DOT 1 (3325 3125);
DOT 1 (3325 3075);
DOT 1 (3325 3025);
DOT 1 (3325 2975);
DOT 1 (3325 2925);
DOT 1 (3325 2825);
DOT 1 (3325 2725);
DOT 1 (3325 2575);
DOT 1 (3325 2625);
DOT 1 (3325 2675);
DOT 1 (3325 2525);
DOT 1 (3325 2475);
DOT 1 (3325 2425);
DOT 1 (3325 2325);
DOT 1 (3325 2375);
DOT 1 (3325 2275);
DOT 1 (3325 2225);
DOT 1 (3325 2125);
DOT 1 (3325 2075);
DOT 1 (3325 2175);
DOT 1 (3325 2025);
DOT 1 (3325 1975);
DOT 1 (3325 1925);
DOT 1 (3325 1875);
DOT 1 (3325 1825);
DOT 1 (3325 1775);
DOT 1 (3325 1725);
DOT 1 (3325 1675);
DOT 1 (3325 1575);
DOT 1 (3325 1625);
DOT 1 (3325 1525);
DOT 1 (3325 1475);
DOT 1 (3325 1425);
DOT 1 (3325 1375);
DOT 1 (3325 1325);
DOT 1 (3325 1275);
DOT 1 (3325 1225);
DOT 1 (3325 1175);
DOT 1 (3325 1075);
DOT 1 (3325 1125);
DOT 1 (3325 1025);
DOT 1 (3325 925);
DOT 1 (3325 975);
DOT 1 (3325 825);
DOT 1 (3325 875);
DOT 1 (3325 775);
DOT 1 (3325 725);
DOT 1 (1625 325);
DOT 1 (2250 -150);
DOT 1 (5025 725);
DOT 1 (5025 675);
DOT 1 (5025 625);
FORCENOTE
20210728 MODIFY FOR GT
(-4025 4650) 0;
DISPLAY LEFT (-4025 4650);
DISPLAY 2.510638 (-4025 4650);
PAINT PINK (-4025 4650);
QUIT
